G04 ================== begin FILE IDENTIFICATION RECORD ==================*
G04 Layout Name:  9054_F0T_PDB_BD_GPU_F_V04_1213_1550.brd*
G04 Film Name:    vcc*
G04 File Format:  Gerber RS274X*
G04 File Origin:  Cadence Allegro 17.2-S081*
G04 Origin Date:  Wed Dec 28 10:19:02 2022*
G04 *
G04 Layer:  DRAWING FORMAT/TITLE_BLOCK_A*
G04 Layer:  PIN/SPECIAL_DRILL*
G04 Layer:  DRAWING FORMAT/TITLE_BLOCK*
G04 Layer:  VIA CLASS/VCC*
G04 Layer:  PIN/VCC*
G04 Layer:  MANUFACTURING/PHOTOPLOT_OUTLINE*
G04 Layer:  ETCH/VCC*
G04 Layer:  DRAWING FORMAT/TITLE_DATA_VCC*
G04 *
G04 Offset:    (0.00 0.00)*
G04 Mirror:    No*
G04 Mode:      Negative*
G04 Rotation:  0*
G04 FullContactRelief:  No*
G04 UndefLineWidth:     6.00*
G04 ================== end FILE IDENTIFICATION RECORD ====================*
%FSLAX25Y25*MOIN*%
%IR0*IPPOS*OFA0.00000B0.00000*MIA0B0*SFA1.00000B1.00000*%
%ADD11C,.03*%
%ADD43C,.042*%
%ADD49C,.061*%
%ADD19C,.07*%
%ADD42C,.026*%
%ADD20C,.07*%
%AMMACRO15*
4,1,36,0.0,.01,
-.001736,.009848,
-.00342,.009397,
-.005,.00866,
-.006428,.00766,
-.00766,.006428,
-.00866,.005,
-.009397,.00342,
-.009848,.001736,
-.01,0.0,
-.009848,-.001736,
-.009397,-.00342,
-.00866,-.005,
-.00766,-.006428,
-.006428,-.00766,
-.005,-.00866,
-.00342,-.009397,
-.001736,-.009848,
0.0,-.01,
.001736,-.009848,
.00342,-.009397,
.005,-.00866,
.006428,-.00766,
.00766,-.006428,
.00866,-.005,
.009397,-.00342,
.009848,-.001736,
.01,0.0,
.009848,.001736,
.009397,.00342,
.00866,.005,
.00766,.006428,
.006428,.00766,
.005,.00866,
.00342,.009397,
.001736,.009848,
0.0,.01,
0.0*
%
%ADD15MACRO15*%
%AMMACRO44*
4,1,36,.0025,0.0,
.002462,.000434,
.002349,.000855,
.002165,.00125,
.001915,.001607,
.001607,.001915,
.00125,.002165,
.000855,.002349,
.000434,.002462,
0.0,.0025,
-.000434,.002462,
-.000855,.002349,
-.00125,.002165,
-.001607,.001915,
-.001915,.001607,
-.002165,.00125,
-.002349,.000855,
-.002462,.000434,
-.0025,0.0,
-.002462,-.000434,
-.002349,-.000855,
-.002165,-.00125,
-.001915,-.001607,
-.001607,-.001915,
-.00125,-.002165,
-.000855,-.002349,
-.000434,-.002462,
0.0,-.0025,
.000434,-.002462,
.000855,-.002349,
.00125,-.002165,
.001607,-.001915,
.001915,-.001607,
.002165,-.00125,
.002349,-.000855,
.002462,-.000434,
.0025,0.0,
270.*
%
%ADD44MACRO44*%
%AMMACRO29*
4,1,36,.0025,0.0,
.002462,.000434,
.002349,.000855,
.002165,.00125,
.001915,.001607,
.001607,.001915,
.00125,.002165,
.000855,.002349,
.000434,.002462,
0.0,.0025,
-.000434,.002462,
-.000855,.002349,
-.00125,.002165,
-.001607,.001915,
-.001915,.001607,
-.002165,.00125,
-.002349,.000855,
-.002462,.000434,
-.0025,0.0,
-.002462,-.000434,
-.002349,-.000855,
-.002165,-.00125,
-.001915,-.001607,
-.001607,-.001915,
-.00125,-.002165,
-.000855,-.002349,
-.000434,-.002462,
0.0,-.0025,
.000434,-.002462,
.000855,-.002349,
.00125,-.002165,
.001607,-.001915,
.001915,-.001607,
.002165,-.00125,
.002349,-.000855,
.002462,-.000434,
.0025,0.0,
180.*
%
%ADD29MACRO29*%
%ADD37C,.066*%
%ADD34C,.06015*%
%ADD31C,.087*%
%AMMACRO18*
4,1,36,0.0,.0135,
-.002344,.013295,
-.004617,.012686,
-.00675,.011691,
-.008678,.010342,
-.010342,.008678,
-.011691,.00675,
-.012686,.004617,
-.013295,.002344,
-.0135,0.0,
-.013295,-.002344,
-.012686,-.004617,
-.011691,-.00675,
-.010342,-.008678,
-.008678,-.010342,
-.00675,-.011691,
-.004617,-.012686,
-.002344,-.013295,
0.0,-.0135,
.002344,-.013295,
.004617,-.012686,
.00675,-.011691,
.008678,-.010342,
.010342,-.008678,
.011691,-.00675,
.012686,-.004617,
.013295,-.002344,
.0135,0.0,
.013295,.002344,
.012686,.004617,
.011691,.00675,
.010342,.008678,
.008678,.010342,
.00675,.011691,
.004617,.012686,
.002344,.013295,
0.0,.0135,
0.0*
%
%ADD18MACRO18*%
%AMMACRO45*
4,1,17,.09027,.06198,
.099661,.045363,
.106024,.027368,
.109166,.008541,
.108991,-.010545,
.105504,-.029311,
.098811,-.047186,
.09027,-.06198,
.0953,-.06701,
.105488,-.049443,
.112471,-.030374,
.116037,-.010382,
.116077,.009925,
.11259,.029931,
.105682,.049027,
.095563,.066634,
.0953,.06701,
.09027,.06198,
90.*
4,1,17,.06198,-.09027,
.045363,-.099661,
.027368,-.106024,
.008541,-.109166,
-.010545,-.108991,
-.029311,-.105504,
-.047186,-.098811,
-.06198,-.09027,
-.06701,-.0953,
-.049443,-.105488,
-.030374,-.112471,
-.010382,-.116037,
.009925,-.116077,
.029931,-.11259,
.049027,-.105682,
.066634,-.095563,
.06701,-.0953,
.06198,-.09027,
90.*
4,1,17,-.09027,-.06198,
-.099661,-.045363,
-.106024,-.027368,
-.109166,-.008541,
-.108991,.010545,
-.105504,.029311,
-.098811,.047186,
-.09027,.06198,
-.0953,.06701,
-.105488,.049443,
-.112471,.030374,
-.116037,.010382,
-.116077,-.009925,
-.11259,-.029931,
-.105682,-.049027,
-.095563,-.066634,
-.0953,-.06701,
-.09027,-.06198,
90.*
4,1,17,-.06198,.09027,
-.045363,.099661,
-.027368,.106024,
-.008541,.109166,
.010545,.108991,
.029311,.105504,
.047186,.098811,
.06198,.09027,
.06701,.0953,
.049443,.105488,
.030374,.112471,
.010382,.116037,
-.009925,.116077,
-.029931,.11259,
-.049027,.105682,
-.066634,.095563,
-.06701,.0953,
-.06198,.09027,
90.*
%
%ADD45MACRO45*%
%ADD21C,.04952*%
%AMMACRO47*
4,1,15,.02475,.01414,
.026829,.009627,
.028094,.004822,
.028504,-.000129,
.028049,-.005077,
.026741,-.009871,
.02475,-.01414,
.02984,-.01923,
.032726,-.013756,
.034617,-.007864,
.035457,-.001734,
.03522,.00445,
.033912,.010498,
.031574,.016227,
.02984,.01923,
.02475,.01414,
90.*
4,1,15,.01414,-.02475,
.009627,-.026829,
.004822,-.028094,
-.000129,-.028504,
-.005077,-.028049,
-.009871,-.026741,
-.01414,-.02475,
-.01923,-.02984,
-.013756,-.032726,
-.007864,-.034617,
-.001734,-.035457,
.00445,-.03522,
.010498,-.033912,
.016227,-.031574,
.01923,-.02984,
.01414,-.02475,
90.*
4,1,15,-.02475,-.01414,
-.026829,-.009627,
-.028094,-.004822,
-.028504,.000129,
-.028049,.005077,
-.026741,.009871,
-.02475,.01414,
-.02984,.01923,
-.032726,.013756,
-.034617,.007864,
-.035457,.001734,
-.03522,-.00445,
-.033912,-.010498,
-.031574,-.016227,
-.02984,-.01923,
-.02475,-.01414,
90.*
4,1,15,-.01414,.02475,
-.009627,.026829,
-.004822,.028094,
.000129,.028504,
.005077,.028049,
.009871,.026741,
.01414,.02475,
.01923,.02984,
.013756,.032726,
.007864,.034617,
.001734,.035457,
-.00445,.03522,
-.010498,.033912,
-.016227,.031574,
-.01923,.02984,
-.01414,.02475,
90.*
%
%ADD47MACRO47*%
%AMMACRO38*
4,1,16,.02657,.01597,
.02894,.011114,
.03043,.005919,
.030995,.000545,
.030619,-.004845,
.029313,-.010088,
.027115,-.015025,
.02657,-.01597,
.03164,-.02104,
.034813,-.015226,
.036928,-.00895,
.037921,-.002401,
.037762,.00422,
.036455,.010713,
.034041,.016881,
.03164,.02104,
.02657,.01597,
90.*
4,1,16,.01597,-.02657,
.011114,-.02894,
.005919,-.03043,
.000545,-.030995,
-.004845,-.030619,
-.010088,-.029313,
-.015025,-.027115,
-.01597,-.02657,
-.02104,-.03164,
-.015226,-.034813,
-.00895,-.036928,
-.002401,-.037921,
.00422,-.037762,
.010713,-.036455,
.016881,-.034041,
.02104,-.03164,
.01597,-.02657,
90.*
4,1,16,-.02657,-.01597,
-.02894,-.011114,
-.03043,-.005919,
-.030995,-.000545,
-.030619,.004845,
-.029313,.010088,
-.027115,.015025,
-.02657,.01597,
-.03164,.02104,
-.034813,.015226,
-.036928,.00895,
-.037921,.002401,
-.037762,-.00422,
-.036455,-.010713,
-.034041,-.016881,
-.03164,-.02104,
-.02657,-.01597,
90.*
4,1,16,-.01597,.02657,
-.011114,.02894,
-.005919,.03043,
-.000545,.030995,
.004845,.030619,
.010088,.029313,
.015025,.027115,
.01597,.02657,
.02104,.03164,
.015226,.034813,
.00895,.036928,
.002401,.037921,
-.00422,.037762,
-.010713,.036455,
-.016881,.034041,
-.02104,.03164,
-.01597,.02657,
90.*
%
%ADD38MACRO38*%
%AMMACRO41*
4,1,15,.03682,.01914,
.039584,.012455,
.041146,.005393,
.041457,-.001834,
.040509,-.009005,
.03833,-.015903,
.03682,-.01914,
.04197,-.0243,
.045552,-.016643,
.04775,-.00848,
.048497,-.000059,
.047771,.008363,
.045593,.016531,
.042029,.024197,
.04197,.0243,
.03682,.01914,
90.*
4,1,15,.01914,-.03682,
.012455,-.039584,
.005393,-.041146,
-.001834,-.041457,
-.009005,-.040509,
-.015903,-.03833,
-.01914,-.03682,
-.0243,-.04197,
-.016643,-.045552,
-.00848,-.04775,
-.000059,-.048497,
.008363,-.047771,
.016531,-.045593,
.024197,-.042029,
.0243,-.04197,
.01914,-.03682,
90.*
4,1,15,-.03682,-.01914,
-.039584,-.012455,
-.041146,-.005393,
-.041457,.001834,
-.040509,.009005,
-.03833,.015903,
-.03682,.01914,
-.04197,.0243,
-.045552,.016643,
-.04775,.00848,
-.048497,.000059,
-.047771,-.008363,
-.045593,-.016531,
-.042029,-.024197,
-.04197,-.0243,
-.03682,-.01914,
90.*
4,1,15,-.01914,.03682,
-.012455,.039584,
-.005393,.041146,
.001834,.041457,
.009005,.040509,
.015903,.03833,
.01914,.03682,
.0243,.04197,
.016643,.045552,
.00848,.04775,
.000059,.048497,
-.008363,.047771,
-.016531,.045593,
-.024197,.042029,
-.0243,.04197,
-.01914,.03682,
90.*
%
%ADD41MACRO41*%
%AMMACRO40*
4,1,15,-.03682,.01914,
-.039584,.012455,
-.041146,.005393,
-.041457,-.001834,
-.040509,-.009005,
-.03833,-.015903,
-.03682,-.01914,
-.04197,-.0243,
-.045552,-.016643,
-.04775,-.00848,
-.048497,-.000059,
-.047771,.008363,
-.045593,.016531,
-.042029,.024197,
-.04197,.0243,
-.03682,.01914,
90.*
4,1,15,-.01914,-.03682,
-.012455,-.039584,
-.005393,-.041146,
.001834,-.041457,
.009005,-.040509,
.015903,-.03833,
.01914,-.03682,
.0243,-.04197,
.016643,-.045552,
.00848,-.04775,
.000059,-.048497,
-.008363,-.047771,
-.016531,-.045593,
-.024197,-.042029,
-.0243,-.04197,
-.01914,-.03682,
90.*
4,1,15,.03682,-.01914,
.039584,-.012455,
.041146,-.005393,
.041457,.001834,
.040509,.009005,
.03833,.015903,
.03682,.01914,
.04197,.0243,
.045552,.016643,
.04775,.00848,
.048497,.000059,
.047771,-.008363,
.045593,-.016531,
.042029,-.024197,
.04197,-.0243,
.03682,-.01914,
90.*
4,1,15,.01914,.03682,
.012455,.039584,
.005393,.041146,
-.001834,.041457,
-.009005,.040509,
-.015903,.03833,
-.01914,.03682,
-.0243,.04197,
-.016643,.045552,
-.00848,.04775,
-.000059,.048497,
.008363,.047771,
.016531,.045593,
.024197,.042029,
.0243,.04197,
.01914,.03682,
90.*
%
%ADD40MACRO40*%
%ADD25C,.113*%
%AMMACRO14*
4,1,36,0.0,.005,
.000868,.004924,
.00171,.004698,
.0025,.00433,
.003214,.00383,
.00383,.003214,
.00433,.0025,
.004698,.00171,
.004924,.000868,
.005,0.0,
.004924,-.000868,
.004698,-.00171,
.00433,-.0025,
.00383,-.003214,
.003214,-.00383,
.0025,-.00433,
.00171,-.004698,
.000868,-.004924,
0.0,-.005,
-.000868,-.004924,
-.00171,-.004698,
-.0025,-.00433,
-.003214,-.00383,
-.00383,-.003214,
-.00433,-.0025,
-.004698,-.00171,
-.004924,-.000868,
-.005,0.0,
-.004924,.000868,
-.004698,.00171,
-.00433,.0025,
-.00383,.003214,
-.003214,.00383,
-.0025,.00433,
-.00171,.004698,
-.000868,.004924,
0.0,.005,
180.*
%
%ADD14MACRO14*%
%ADD28C,.115*%
%ADD48C,.116*%
%ADD10C,.125*%
%ADD23C,.155*%
%ADD35C,.256*%
%AMMACRO26*
4,1,36,0.0,.0135,
-.002344,.013295,
-.004617,.012686,
-.00675,.011691,
-.008678,.010342,
-.010342,.008678,
-.011691,.00675,
-.012686,.004617,
-.013295,.002344,
-.0135,0.0,
-.013295,-.002344,
-.012686,-.004617,
-.011691,-.00675,
-.010342,-.008678,
-.008678,-.010342,
-.00675,-.011691,
-.004617,-.012686,
-.002344,-.013295,
0.0,-.0135,
.002344,-.013295,
.004617,-.012686,
.00675,-.011691,
.008678,-.010342,
.010342,-.008678,
.011691,-.00675,
.012686,-.004617,
.013295,-.002344,
.0135,0.0,
.013295,.002344,
.012686,.004617,
.011691,.00675,
.010342,.008678,
.008678,.010342,
.00675,.011691,
.004617,.012686,
.002344,.013295,
0.0,.0135,
270.*
%
%ADD26MACRO26*%
%AMMACRO22*
4,1,36,0.0,.0135,
-.002344,.013295,
-.004617,.012686,
-.00675,.011691,
-.008678,.010342,
-.010342,.008678,
-.011691,.00675,
-.012686,.004617,
-.013295,.002344,
-.0135,0.0,
-.013295,-.002344,
-.012686,-.004617,
-.011691,-.00675,
-.010342,-.008678,
-.008678,-.010342,
-.00675,-.011691,
-.004617,-.012686,
-.002344,-.013295,
0.0,-.0135,
.002344,-.013295,
.004617,-.012686,
.00675,-.011691,
.008678,-.010342,
.010342,-.008678,
.011691,-.00675,
.012686,-.004617,
.013295,-.002344,
.0135,0.0,
.013295,.002344,
.012686,.004617,
.011691,.00675,
.010342,.008678,
.008678,.010342,
.00675,.011691,
.004617,.012686,
.002344,.013295,
0.0,.0135,
180.*
%
%ADD22MACRO22*%
%AMMACRO24*
4,1,36,.0025,0.0,
.002462,.000434,
.002349,.000855,
.002165,.00125,
.001915,.001607,
.001607,.001915,
.00125,.002165,
.000855,.002349,
.000434,.002462,
0.0,.0025,
-.000434,.002462,
-.000855,.002349,
-.00125,.002165,
-.001607,.001915,
-.001915,.001607,
-.002165,.00125,
-.002349,.000855,
-.002462,.000434,
-.0025,0.0,
-.002462,-.000434,
-.002349,-.000855,
-.002165,-.00125,
-.001915,-.001607,
-.001607,-.001915,
-.00125,-.002165,
-.000855,-.002349,
-.000434,-.002462,
0.0,-.0025,
.000434,-.002462,
.000855,-.002349,
.00125,-.002165,
.001607,-.001915,
.001915,-.001607,
.002165,-.00125,
.002349,-.000855,
.002462,-.000434,
.0025,0.0,
90.*
%
%ADD24MACRO24*%
%ADD36C,.187*%
%AMMACRO33*
4,1,36,0.0,.019,
-.003299,.018711,
-.006498,.017854,
-.0095,.016454,
-.012213,.014555,
-.014555,.012213,
-.016454,.0095,
-.017854,.006498,
-.018711,.003299,
-.019,0.0,
-.018711,-.003299,
-.017854,-.006498,
-.016454,-.0095,
-.014555,-.012213,
-.012213,-.014555,
-.0095,-.016454,
-.006498,-.017854,
-.003299,-.018711,
0.0,-.019,
.003299,-.018711,
.006498,-.017854,
.0095,-.016454,
.012213,-.014555,
.014555,-.012213,
.016454,-.0095,
.017854,-.006498,
.018711,-.003299,
.019,0.0,
.018711,.003299,
.017854,.006498,
.016454,.0095,
.014555,.012213,
.012213,.014555,
.0095,.016454,
.006498,.017854,
.003299,.018711,
0.0,.019,
180.*
%
%ADD33MACRO33*%
%AMMACRO17*
4,1,36,.0025,0.0,
.002462,.000434,
.002349,.000855,
.002165,.00125,
.001915,.001607,
.001607,.001915,
.00125,.002165,
.000855,.002349,
.000434,.002462,
0.0,.0025,
-.000434,.002462,
-.000855,.002349,
-.00125,.002165,
-.001607,.001915,
-.001915,.001607,
-.002165,.00125,
-.002349,.000855,
-.002462,.000434,
-.0025,0.0,
-.002462,-.000434,
-.002349,-.000855,
-.002165,-.00125,
-.001915,-.001607,
-.001607,-.001915,
-.00125,-.002165,
-.000855,-.002349,
-.000434,-.002462,
0.0,-.0025,
.000434,-.002462,
.000855,-.002349,
.00125,-.002165,
.001607,-.001915,
.001915,-.001607,
.002165,-.00125,
.002349,-.000855,
.002462,-.000434,
.0025,0.0,
0.0*
%
%ADD17MACRO17*%
%ADD16C,.188*%
%AMMACRO46*
4,1,21,-.0075,-.06379,
-.0075,-.0709,
-.015443,-.068892,
-.022917,-.065536,
-.029695,-.060932,
-.03557,-.055222,
-.040364,-.048578,
-.043932,-.041203,
-.046165,-.03332,
-.046995,-.025169,
-.047,-.0245,
-.047,-.0075,
-.04,-.0075,
-.04,-.0245,
-.039392,-.031446,
-.037588,-.038181,
-.034641,-.0445,
-.030642,-.050211,
-.025712,-.055141,
-.02,-.05914,
-.013681,-.062087,
-.0075,-.06379,
90.*
4,1,21,.0075,-.0709,
.0075,-.06379,
.014209,-.061891,
.020486,-.058856,
.02614,-.054776,
.031001,-.049777,
.034919,-.04401,
.037776,-.03765,
.039486,-.030891,
.04,-.0245,
.04,-.0075,
.047,-.0075,
.047,-.0245,
.046286,-.032662,
.044165,-.040576,
.040703,-.048001,
.036003,-.054713,
.03021,-.060506,
.023499,-.065205,
.016073,-.068668,
.008159,-.070789,
.0075,-.0709,
90.*
4,1,21,-.0075,.0709,
-.0075,.06379,
-.014209,.061891,
-.020486,.058856,
-.02614,.054776,
-.031001,.049777,
-.034919,.04401,
-.037776,.03765,
-.039486,.030891,
-.04,.0245,
-.04,.0075,
-.047,.0075,
-.047,.0245,
-.046286,.032662,
-.044165,.040576,
-.040703,.048001,
-.036003,.054713,
-.03021,.060506,
-.023499,.065205,
-.016073,.068668,
-.008159,.070789,
-.0075,.0709,
90.*
4,1,21,.0075,.06379,
.0075,.0709,
.015443,.068892,
.022917,.065536,
.029695,.060932,
.03557,.055222,
.040364,.048578,
.043932,.041203,
.046165,.03332,
.046995,.025169,
.047,.0245,
.047,.0075,
.04,.0075,
.04,.0245,
.039392,.031446,
.037588,.038181,
.034641,.0445,
.030642,.050211,
.025712,.055141,
.02,.05914,
.013681,.062087,
.0075,.06379,
90.*
%
%ADD46MACRO46*%
%AMMACRO39*
4,1,16,.02657,.01597,
.02894,.011114,
.03043,.005919,
.030995,.000545,
.030619,-.004845,
.029313,-.010088,
.027115,-.015025,
.02657,-.01597,
.03164,-.02104,
.034813,-.015226,
.036928,-.00895,
.037921,-.002401,
.037762,.00422,
.036455,.010713,
.034041,.016881,
.03164,.02104,
.02657,.01597,
270.*
4,1,16,.01597,-.02657,
.011114,-.02894,
.005919,-.03043,
.000545,-.030995,
-.004845,-.030619,
-.010088,-.029313,
-.015025,-.027115,
-.01597,-.02657,
-.02104,-.03164,
-.015226,-.034813,
-.00895,-.036928,
-.002401,-.037921,
.00422,-.037762,
.010713,-.036455,
.016881,-.034041,
.02104,-.03164,
.01597,-.02657,
270.*
4,1,16,-.02657,-.01597,
-.02894,-.011114,
-.03043,-.005919,
-.030995,-.000545,
-.030619,.004845,
-.029313,.010088,
-.027115,.015025,
-.02657,.01597,
-.03164,.02104,
-.034813,.015226,
-.036928,.00895,
-.037921,.002401,
-.037762,-.00422,
-.036455,-.010713,
-.034041,-.016881,
-.03164,-.02104,
-.02657,-.01597,
270.*
4,1,16,-.01597,.02657,
-.011114,.02894,
-.005919,.03043,
-.000545,.030995,
.004845,.030619,
.010088,.029313,
.015025,.027115,
.01597,.02657,
.02104,.03164,
.015226,.034813,
.00895,.036928,
.002401,.037921,
-.00422,.037762,
-.010713,.036455,
-.016881,.034041,
-.02104,.03164,
-.01597,.02657,
270.*
%
%ADD39MACRO39*%
%AMMACRO12*
4,1,18,.10783,.07955,
.120006,.059617,
.128535,.037873,
.133159,.014977,
.133736,-.008373,
.130251,-.031469,
.122807,-.053609,
.111633,-.074119,
.10783,-.07955,
.11284,-.08455,
.125808,-.063671,
.134953,-.040857,
.139997,-.016802,
.140788,.007763,
.137301,.032093,
.129642,.055447,
.118045,.077117,
.11284,.08455,
.10783,.07955,
180.*
4,1,18,.07955,-.10783,
.059617,-.120006,
.037873,-.128535,
.014977,-.133159,
-.008373,-.133736,
-.031469,-.130251,
-.053609,-.122807,
-.074119,-.111633,
-.07955,-.10783,
-.08455,-.11284,
-.063671,-.125808,
-.040857,-.134953,
-.016802,-.139997,
.007763,-.140788,
.032093,-.137301,
.055447,-.129642,
.077117,-.118045,
.08455,-.11284,
.07955,-.10783,
180.*
4,1,18,-.10783,-.07955,
-.120006,-.059617,
-.128535,-.037873,
-.133159,-.014977,
-.133736,.008373,
-.130251,.031469,
-.122807,.053609,
-.111633,.074119,
-.10783,.07955,
-.11284,.08455,
-.125808,.063671,
-.134953,.040857,
-.139997,.016802,
-.140788,-.007763,
-.137301,-.032093,
-.129642,-.055447,
-.118045,-.077117,
-.11284,-.08455,
-.10783,-.07955,
180.*
4,1,18,-.07955,.10783,
-.059617,.120006,
-.037873,.128535,
-.014977,.133159,
.008373,.133736,
.031469,.130251,
.053609,.122807,
.074119,.111633,
.07955,.10783,
.08455,.11284,
.063671,.125808,
.040857,.134953,
.016802,.139997,
-.007763,.140788,
-.032093,.137301,
-.055447,.129642,
-.077117,.118045,
-.08455,.11284,
-.07955,.10783,
180.*
%
%ADD12MACRO12*%
%AMMACRO30*
4,1,15,.03682,.01914,
.039584,.012455,
.041146,.005393,
.041457,-.001834,
.040509,-.009005,
.03833,-.015903,
.03682,-.01914,
.04197,-.0243,
.045552,-.016643,
.04775,-.00848,
.048497,-.000059,
.047771,.008363,
.045593,.016531,
.042029,.024197,
.04197,.0243,
.03682,.01914,
270.*
4,1,15,.01914,-.03682,
.012455,-.039584,
.005393,-.041146,
-.001834,-.041457,
-.009005,-.040509,
-.015903,-.03833,
-.01914,-.03682,
-.0243,-.04197,
-.016643,-.045552,
-.00848,-.04775,
-.000059,-.048497,
.008363,-.047771,
.016531,-.045593,
.024197,-.042029,
.0243,-.04197,
.01914,-.03682,
270.*
4,1,15,-.03682,-.01914,
-.039584,-.012455,
-.041146,-.005393,
-.041457,.001834,
-.040509,.009005,
-.03833,.015903,
-.03682,.01914,
-.04197,.0243,
-.045552,.016643,
-.04775,.00848,
-.048497,.000059,
-.047771,-.008363,
-.045593,-.016531,
-.042029,-.024197,
-.04197,-.0243,
-.03682,-.01914,
270.*
4,1,15,-.01914,.03682,
-.012455,.039584,
-.005393,.041146,
.001834,.041457,
.009005,.040509,
.015903,.03833,
.01914,.03682,
.0243,.04197,
.016643,.045552,
.00848,.04775,
.000059,.048497,
-.008363,.047771,
-.016531,.045593,
-.024197,.042029,
-.0243,.04197,
-.01914,.03682,
270.*
%
%ADD30MACRO30*%
%AMMACRO32*
4,1,15,-.03682,.01914,
-.039584,.012455,
-.041146,.005393,
-.041457,-.001834,
-.040509,-.009005,
-.03833,-.015903,
-.03682,-.01914,
-.04197,-.0243,
-.045552,-.016643,
-.04775,-.00848,
-.048497,-.000059,
-.047771,.008363,
-.045593,.016531,
-.042029,.024197,
-.04197,.0243,
-.03682,.01914,
270.*
4,1,15,-.01914,-.03682,
-.012455,-.039584,
-.005393,-.041146,
.001834,-.041457,
.009005,-.040509,
.015903,-.03833,
.01914,-.03682,
.0243,-.04197,
.016643,-.045552,
.00848,-.04775,
.000059,-.048497,
-.008363,-.047771,
-.016531,-.045593,
-.024197,-.042029,
-.0243,-.04197,
-.01914,-.03682,
270.*
4,1,15,.03682,-.01914,
.039584,-.012455,
.041146,-.005393,
.041457,.001834,
.040509,.009005,
.03833,.015903,
.03682,.01914,
.04197,.0243,
.045552,.016643,
.04775,.00848,
.048497,.000059,
.047771,-.008363,
.045593,-.016531,
.042029,-.024197,
.04197,-.0243,
.03682,-.01914,
270.*
4,1,15,.01914,.03682,
.012455,.039584,
.005393,.041146,
-.001834,.041457,
-.009005,.040509,
-.015903,.03833,
-.01914,.03682,
-.0243,.04197,
-.016643,.045552,
-.00848,.04775,
-.000059,.048497,
.008363,.047771,
.016531,.045593,
.024197,.042029,
.0243,.04197,
.01914,.03682,
270.*
%
%ADD32MACRO32*%
%ADD50C,.02*%
%ADD51C,.006*%
%ADD59C,.07006*%
%ADD57C,.08008*%
%ADD60C,.09558*%
%ADD64C,.11022*%
%ADD58C,.12006*%
%ADD62C,.185*%
%ADD54C,.1175*%
%ADD65C,.12606*%
%ADD56O,.40438X.60123*%
%ADD55C,.1195*%
%ADD53C,.16506*%
%ADD63C,.28606*%
%ADD61C,.45382*%
%ADD52C,.19806*%
G75*
%LPD*%
G75*
G36*
G01X-457143Y-1211429D02*
X4308572D01*
Y2242857D01*
X-457143D01*
Y-1211429D01*
G37*
%LPC*%
G75*
G36*
G01X76695Y619228D02*
X86605D01*
G02X86747Y619169I0J-200D01*
G01X89329Y616587D01*
G02X89388Y616445I-141J-142D01*
G01Y177012D01*
G03X89974Y175598I1999J0D01*
G01X131090Y134482D01*
X131120Y134398D01*
X131115Y134353D01*
G03X131098Y134000I3485J-345D01*
G03X134600Y130498I3502J0D01*
G03X134962Y130516I7J3502D01*
G02X135112Y130470I21J-199D01*
G03X136400Y130000I1288J1530D01*
G01X227015D01*
G02X227157Y129941I0J-200D01*
G01X227534Y129564D01*
X227564Y129489D01*
X227562Y129447D01*
G03X227561Y129365I2999J-78D01*
G01Y88313D01*
G02X227461Y88140I-200J0D01*
G03X223348Y81000I4139J-7139D01*
G03X227461Y73860I8252J-1D01*
G02X227561Y73687I-100J-173D01*
G01Y6936D01*
G02X227502Y6794I-200J0D01*
G01X224767Y4059D01*
G02X224625Y4000I-142J141D01*
G01X222653D01*
G02X222507Y4064I1J200D01*
G03X220305I-1101J-1023D01*
G02X220159Y4000I-147J136D01*
G01X202653D01*
G02X202507Y4064I1J200D01*
G03X200305I-1101J-1023D01*
G02X200159Y4000I-147J136D01*
G01X182653D01*
G02X182507Y4064I1J200D01*
G03X180305I-1101J-1023D01*
G02X180159Y4000I-147J136D01*
G01X162653D01*
G02X162507Y4064I1J200D01*
G03X160305I-1101J-1023D01*
G02X160159Y4000I-147J136D01*
G01X142653D01*
G02X142507Y4064I1J200D01*
G03X140305I-1101J-1023D01*
G02X140159Y4000I-147J136D01*
G01X122653D01*
G02X122507Y4064I1J200D01*
G03X120305I-1101J-1023D01*
G02X120159Y4000I-147J136D01*
G01X102653D01*
G02X102507Y4064I1J200D01*
G03X100305I-1101J-1023D01*
G02X100159Y4000I-147J136D01*
G01X82653D01*
G02X82507Y4064I1J200D01*
G03X80305I-1101J-1023D01*
G02X80159Y4000I-147J136D01*
G01X31930D01*
G02X31786Y4061I0J200D01*
G03X29632I-1077J-1047D01*
G02X29488Y4000I-144J139D01*
G01X19685D01*
G02X12068Y5974I1J15685D01*
G02X11968Y6111I96J175D01*
G03X10493Y7332I-1475J-280D01*
G03X10179Y7299I-1J-1502D01*
G02X10013Y7337I-43J195D01*
G02X4000Y19685I9672J12348D01*
G01Y22705D01*
G02X4061Y22849I200J0D01*
G03Y25011I-1043J1081D01*
G02X4000Y25155I139J144D01*
G01Y42705D01*
G02X4061Y42849I200J0D01*
G03Y45011I-1043J1081D01*
G02X4000Y45155I139J144D01*
G01Y62705D01*
G02X4061Y62849I200J0D01*
G03Y65011I-1043J1081D01*
G02X4000Y65155I139J144D01*
G01Y82705D01*
G02X4061Y82849I200J0D01*
G03Y85011I-1043J1081D01*
G02X4000Y85155I139J144D01*
G01Y102705D01*
G02X4061Y102849I200J0D01*
G03Y105011I-1043J1081D01*
G02X4000Y105155I139J144D01*
G01Y122705D01*
G02X4061Y122849I200J0D01*
G03Y125011I-1043J1081D01*
G02X4000Y125155I139J144D01*
G01Y142705D01*
G02X4061Y142849I200J0D01*
G03Y145011I-1043J1081D01*
G02X4000Y145155I139J144D01*
G01Y162705D01*
G02X4061Y162849I200J0D01*
G03Y165011I-1043J1081D01*
G02X4000Y165155I139J144D01*
G01Y182705D01*
G02X4061Y182849I200J0D01*
G03Y185011I-1043J1081D01*
G02X4000Y185155I139J144D01*
G01Y202705D01*
G02X4061Y202849I200J0D01*
G03Y205011I-1043J1081D01*
G02X4000Y205155I139J144D01*
G01Y222705D01*
G02X4061Y222849I200J0D01*
G03Y225011I-1043J1081D01*
G02X4000Y225155I139J144D01*
G01Y242705D01*
G02X4061Y242849I200J0D01*
G03Y245011I-1043J1081D01*
G02X4000Y245155I139J144D01*
G01Y262705D01*
G02X4061Y262849I200J0D01*
G03Y265011I-1043J1081D01*
G02X4000Y265155I139J144D01*
G01Y282705D01*
G02X4061Y282849I200J0D01*
G03Y285011I-1043J1081D01*
G02X4000Y285155I139J144D01*
G01Y302705D01*
G02X4061Y302849I200J0D01*
G03Y305011I-1043J1081D01*
G02X4000Y305155I139J144D01*
G01Y322705D01*
G02X4061Y322849I200J0D01*
G03Y325011I-1043J1081D01*
G02X4000Y325155I139J144D01*
G01Y342705D01*
G02X4061Y342849I200J0D01*
G03Y345011I-1043J1081D01*
G02X4000Y345155I139J144D01*
G01Y362705D01*
G02X4061Y362849I200J0D01*
G03Y365011I-1043J1081D01*
G02X4000Y365155I139J144D01*
G01Y382705D01*
G02X4061Y382849I200J0D01*
G03Y385011I-1043J1081D01*
G02X4000Y385155I139J144D01*
G01Y402705D01*
G02X4061Y402849I200J0D01*
G03Y405011I-1043J1081D01*
G02X4000Y405155I139J144D01*
G01Y422705D01*
G02X4061Y422849I200J0D01*
G03Y425011I-1043J1081D01*
G02X4000Y425155I139J144D01*
G01Y442705D01*
G02X4061Y442849I200J0D01*
G03Y445011I-1043J1081D01*
G02X4000Y445155I139J144D01*
G01Y462705D01*
G02X4061Y462849I200J0D01*
G03Y465011I-1043J1081D01*
G02X4000Y465155I139J144D01*
G01Y482705D01*
G02X4061Y482849I200J0D01*
G03Y485011I-1043J1081D01*
G02X4000Y485155I139J144D01*
G01Y502705D01*
G02X4061Y502849I200J0D01*
G03Y505011I-1043J1081D01*
G02X4000Y505155I139J144D01*
G01Y522705D01*
G02X4061Y522849I200J0D01*
G03Y525011I-1043J1081D01*
G02X4000Y525155I139J144D01*
G01Y542705D01*
G02X4061Y542849I200J0D01*
G03Y545011I-1043J1081D01*
G02X4000Y545155I139J144D01*
G01Y562705D01*
G02X4061Y562849I200J0D01*
G03Y565011I-1043J1081D01*
G02X4000Y565155I139J144D01*
G01Y582705D01*
G02X4061Y582849I200J0D01*
G03Y585011I-1043J1081D01*
G02X4000Y585155I139J144D01*
G01Y602705D01*
G02X4061Y602849I200J0D01*
G03X4520Y603930I-1043J1081D01*
G03X4128Y604942I-1502J0D01*
G02X4077Y605096I148J134D01*
G02X14735Y618427I15608J-1553D01*
G02X14898Y618410I63J-190D01*
G03X15642Y618213I744J1306D01*
G03X16913Y618914I0J1503D01*
G02X17048Y619005I170J-106D01*
G02X19685Y619228I2635J-15462D01*
G01X34215D01*
G02X34361Y619165I0J-200D01*
G03X36549I1094J1029D01*
G02X36695Y619228I146J-137D01*
G01X54215D01*
G02X54361Y619165I0J-200D01*
G03X56549I1094J1029D01*
G02X56695Y619228I146J-137D01*
G01X74215D01*
G02X74361Y619165I0J-200D01*
G03X76549I1094J1029D01*
G02X76695Y619228I146J-137D01*
G37*
G36*
G01X1866142Y783851D02*
G02X1872016Y777977I0J-5874D01*
G01Y534528D01*
G02X1866142Y528654I-5874J0D01*
G01X1751968D01*
G02X1742157Y538465I1J9811D01*
G01Y603543D01*
G03X1712598Y633102I-29559J0D01*
G01X1640064D01*
G02X1630253Y642913I0J9811D01*
G01Y738607D01*
G03X1620379Y748481I-9874J0D01*
G01X1383858D01*
G03X1373984Y738607I0J-9874D01*
G01Y435039D01*
G02X1354331Y415386I-19653J0D01*
G01X1154764D01*
G02X1148890Y421260I0J5874D01*
G01Y479449D01*
G03X1135079Y493260I-13811J0D01*
G01X550827D01*
G03X537016Y479449I0J-13811D01*
G01Y421260D01*
G02X531142Y415386I-5874J0D01*
G01X377952D01*
G02X358299Y435039I0J19653D01*
G01Y738607D01*
G03X348425Y748481I-9874J0D01*
G01X111905D01*
G03X102031Y738607I0J-9874D01*
G01Y642913D01*
G02X92220Y633102I-9811J0D01*
G01X7874D01*
G02X2000Y638976I0J5874D01*
G01Y777977D01*
G02X7874Y783851I5874J0D01*
G01X1866142D01*
G37*
G36*
G01X733366Y313888D02*
X733365D01*
G03X730998Y310575I1135J-3313D01*
G03X731331Y309085I3503J1D01*
G02Y308915I-181J-85D01*
G03X730998Y307425I3170J-1491D01*
G03X733365Y304112I3502J0D01*
G01X733366D01*
G02X733500Y303923I-66J-189D01*
G01Y270411D01*
G02X733441Y270269I-200J0D01*
G01X730731Y267559D01*
G02X730589Y267500I-142J141D01*
G01X724911D01*
G02X724769Y267559I0J200D01*
G01X723559Y268769D01*
G02X723500Y268911I141J142D01*
G01Y288756D01*
G02X723580Y288916I200J0D01*
G01X723837Y289108D01*
G02X723957Y289148I120J-160D01*
G01X724013Y289140D01*
G03X725000Y288998I987J3359D01*
G03X728502Y292500I0J3502D01*
G01Y292501D01*
G03X726865Y295465I-3502J0D01*
G01X726772Y295634D01*
G02X726774Y295664I200J2D01*
G01X726828Y296027D01*
G02X726974Y296190I198J-30D01*
G01X726975D01*
G03X729578Y299575I-899J3385D01*
G03X726075Y303078I-3503J0D01*
G03X724510Y302708I2J-3503D01*
G02X724340Y302704I-89J179D01*
G03X722927Y303002I-1414J-3204D01*
G01X722924D01*
G03X720755Y302250I-1J-3503D01*
G01X720631Y302207D01*
X720598Y302210D01*
G03X720265Y302238I-334J-1972D01*
G01X678530D01*
G02X678358Y302336I0J200D01*
G01X678182Y302632D01*
G02X678154Y302734I172J102D01*
G01X678178Y302829D01*
G03X678602Y304499I-3078J1670D01*
G01Y304500D01*
G03X671598I-3502J0D01*
G01Y304499D01*
G03X672022Y302829I3502J0D01*
G01X672046Y302734D01*
G02X672018Y302632I-200J0D01*
G01X671842Y302336D01*
G02X671670Y302238I-172J102D01*
G01X665530D01*
G02X665358Y302336I0J200D01*
G01X665182Y302632D01*
G02X665154Y302734I172J102D01*
G01X665178Y302829D01*
G03X665602Y304499I-3078J1670D01*
G01Y304501D01*
G03X665059Y306374I-3502J0D01*
G02X665061Y306590I169J106D01*
G03X665627Y308498I-2936J1909D01*
G01Y308502D01*
G02X665827Y308702I200J0D01*
G01X665828D01*
G02X665944Y308665I0J-200D01*
G01X665945Y308664D01*
G03X667999Y307998I2055J2836D01*
G01X668000D01*
G03X671502Y311500I0J3502D01*
G01Y311503D01*
G03X671466Y312004I-3502J0D01*
G01Y312005D01*
G02X671500Y312147I198J28D01*
G01X671569Y312246D01*
G02X671693Y312327I164J-115D01*
G03X674502Y315760I-693J3433D01*
G03X667498I-3502J0D01*
G01Y315757D01*
G03X667534Y315256I3502J0D01*
G01Y315255D01*
G02X667500Y315113I-198J-28D01*
G01X667431Y315014D01*
G02X667307Y314933I-164J115D01*
G03X665872Y314281I694J-3433D01*
G02X665628I-122J159D01*
G03X663501Y315002I-2128J-2781D01*
G01X663500D01*
G03X659998Y311500I0J-3502D01*
G03X660000Y311387I3502J5D01*
G02X659925Y311225I-200J-6D01*
G03X658622Y308500I2200J-2726D01*
G01Y308499D01*
G03X659165Y306626I3503J0D01*
G01X659196Y306519D01*
X659164Y306410D01*
G03X658598Y304502I2936J-1909D01*
G01Y304500D01*
G03X661017Y301169I3503J0D01*
G01X661067Y301153D01*
X661138Y301077D01*
X661230Y300694D01*
G02X661177Y300506I-195J-47D01*
G01X660086Y299414D01*
G03X659500Y298000I1413J-1414D01*
G01Y290821D01*
G02X659456Y290695I-200J-1D01*
G03X658682Y288500I2725J-2195D01*
G03X658732Y287914I3502J4D01*
G02X658698Y287764I-197J-34D01*
G01X658535Y287534D01*
X658405Y287452D01*
G03X655498Y284000I596J-3452D01*
G03X658514Y280532I3502J0D01*
G02X658686Y280342I-28J-198D01*
G03X659456Y278305I3497J158D01*
G02X659500Y278179I-156J-125D01*
G01Y275877D01*
G03X660086Y274463I1999J0D01*
G01X668340Y266209D01*
G02X668399Y266067I-141J-142D01*
G01Y237581D01*
G02X668340Y237439I-200J0D01*
G01X666859Y235958D01*
G02X666717Y235899I-142J141D01*
G01X655012D01*
G02X654870Y235958I0J200D01*
G01X654059Y236769D01*
G02X654000Y236911I141J142D01*
G01Y259218D01*
G02X654057Y259357I200J-1D01*
G01X654139Y259442D01*
G02X654272Y259502I143J-140D01*
G01X654273D01*
G03X655595Y259832I-171J3498D01*
G01X655680Y259851D01*
X655765Y259832D01*
G03X657259Y259498I1493J3168D01*
G01X657260D01*
G03X658432Y259700I0J3502D01*
G02X658617Y259673I67J-189D01*
G03X660684Y258998I2067J2827D01*
G03Y266002I0J3502D01*
G01X660681D01*
G03X659511Y265800I2J-3502D01*
G02X659326Y265827I-67J189D01*
G03X657259Y266502I-2067J-2827D01*
G01X657258D01*
G03X655765Y266168I0J-3502D01*
G01X655680Y266149D01*
X655595Y266168D01*
G03X654710Y266449I-1493J-3168D01*
G02X654548Y266611I35J197D01*
G03X654033Y267914I-3449J-610D01*
G01X654000Y268023D01*
Y297500D01*
G03X653414Y298914I-1999J0D01*
G01X650914Y301414D01*
G03X649500Y302000I-1414J-1413D01*
G01X611169D01*
G02X610987Y302118I0J200D01*
G01X610814Y302506D01*
X610832Y302622D01*
X610871Y302666D01*
G03X611762Y305000I-2611J2334D01*
G03X608260Y308502I-3502J0D01*
G01X608258D01*
G03X605466Y307114I0J-3502D01*
G01X605307Y307035D01*
G02X605289Y307036I2J200D01*
G01X604901Y307070D01*
X604815Y307128D01*
X604792Y307173D01*
G03X601675Y309078I-3117J-1598D01*
G03Y302072I0J-3503D01*
G03X604468Y303461I0J3503D01*
G02X604645Y303539I159J-121D01*
G01X605033Y303505D01*
X605119Y303447D01*
X605142Y303402D01*
G03X605647Y302666I3117J1598D01*
G01X605686Y302622D01*
X605704Y302506D01*
X605531Y302118D01*
G02X605349Y302000I-182J82D01*
G01X603881D01*
G03X602467Y301414I0J-1999D01*
G01X600517Y299464D01*
G02X600402Y299407I-142J141D01*
G03X597373Y295937I473J-3470D01*
G03X598741Y293160I3503J0D01*
G01X598819Y293002D01*
Y236246D01*
G02X598760Y236104I-200J0D01*
G01X597815Y235159D01*
G02X597673Y235100I-142J141D01*
G01X589811D01*
G02X589669Y235159I0J200D01*
G01X589400Y235428D01*
G02X589341Y235570I141J142D01*
G01Y262986D01*
G03X588755Y264400I-1999J0D01*
G01X586722Y266433D01*
G03X585308Y267019I-1414J-1413D01*
G01X579797D01*
X579617Y267132D01*
G03X573317I-3150J-1533D01*
G01X573137Y267019D01*
X566389D01*
X566279Y267109D01*
X566265Y267180D01*
G03X565917Y268153I-3435J-680D01*
G01X565893Y268248D01*
X565917Y268343D01*
G03X566334Y270000I-3087J1658D01*
G03X565919Y271654I-3504J0D01*
G01X565896Y271747D01*
X565920Y271842D01*
G03X566336Y273498I-3091J1657D01*
G01Y273500D01*
G03X565920Y275156I-3506J0D01*
G02Y275344I177J94D01*
G03X566336Y277000I-3090J1656D01*
G03X559324I-3506J0D01*
G03X559740Y275344I3506J0D01*
G02Y275156I-177J-94D01*
G03X559324Y273500I3090J-1656D01*
G01Y273498D01*
G03X559740Y271842I3507J1D01*
G01X559764Y271747D01*
X559741Y271654D01*
G03X559326Y270000I3089J-1654D01*
G03X559743Y268343I3504J1D01*
G01X559767Y268248D01*
X559743Y268153D01*
G03X559395Y267180I3087J-1653D01*
G01X559381Y267109D01*
X559271Y267019D01*
X554760D01*
X554580Y267132D01*
G03X548280I-3150J-1533D01*
G01X548100Y267019D01*
X543650D01*
G02X543508Y267078I0J200D01*
G01X540904Y269682D01*
G02X540845Y269824I141J142D01*
G01Y314530D01*
G03X540259Y315944I-1999J0D01*
G01X537789Y318414D01*
G03X536375Y319000I-1414J-1413D01*
G01X520319D01*
G02X520137Y319118I0J200D01*
G01X519964Y319506D01*
X519982Y319622D01*
X520021Y319666D01*
G03X520912Y322000I-2611J2334D01*
G03X518959Y325141I-3502J0D01*
G02X518847Y325320I88J180D01*
G01Y325679D01*
G02X518959Y325858I200J-1D01*
G03X520912Y328998I-1550J3141D01*
G01Y329000D01*
G03X513908I-3502J0D01*
G03X515860Y325859I3503J0D01*
G02X515972Y325680I-88J-180D01*
G01Y325321D01*
G02X515860Y325142I-200J1D01*
G03X513906Y322000I1549J-3142D01*
G03X514797Y319666I3502J0D01*
G01X514836Y319622D01*
X514854Y319506D01*
X514681Y319118D01*
G02X514499Y319000I-182J82D01*
G01X509219D01*
G02X509037Y319118I0J200D01*
G01X508864Y319506D01*
X508882Y319622D01*
X508921Y319666D01*
G03X509812Y322000I-2611J2334D01*
G03X507859Y325141I-3502J0D01*
G02X507747Y325320I88J180D01*
G01Y325680D01*
G02X507859Y325859I200J-1D01*
G03X509812Y329000I-1549J3141D01*
G03X502806I-3503J0D01*
G03X504759Y325859I3502J0D01*
G02X504871Y325680I-88J-180D01*
G01Y325320D01*
G02X504759Y325141I-200J1D01*
G03X502806Y322000I1549J-3141D01*
G03X503697Y319666I3502J0D01*
G01X503736Y319622D01*
X503754Y319506D01*
X503581Y319118D01*
G02X503399Y319000I-182J82D01*
G01X486100D01*
G03X484686Y318414I0J-1999D01*
G01X482186Y315914D01*
G03X481600Y314500I1413J-1414D01*
G01Y36633D01*
G02X481400Y36433I-200J0D01*
G01X387878D01*
G02X387736Y36492I0J200D01*
G01X290814Y133414D01*
G03X289400Y134000I-1414J-1413D01*
G01X138296D01*
G02X138097Y134188I1J200D01*
G01Y134189D01*
G03X134600Y137502I-3497J-189D01*
G01X134599D01*
G03X133919Y137435I2J-3502D01*
G01X133917D01*
G02X133738Y137490I-38J196D01*
G01X93447Y177781D01*
G02X93388Y177923I141J142D01*
G01Y616445D01*
G02X93447Y616587I200J0D01*
G01X93856Y616996D01*
X93977Y617018D01*
X94034Y616993D01*
G03X95454Y616692I1420J3201D01*
G01X95455D01*
G03X98779Y619091I0J3502D01*
G01X98799Y619152D01*
X98904Y619228D01*
X102364D01*
G03X112340Y621432I-1J23684D01*
G01X112425Y621451D01*
X112559Y621399D01*
G03X114923Y620480I2364J2581D01*
G03X118425Y623982I0J3502D01*
G03X118222Y625156I-3502J-1D01*
G01X118210Y625223D01*
X118276Y625371D01*
G03X125158Y636484I-15914J17542D01*
G01X125326Y636629D01*
G03X128403Y640105I-425J3476D01*
G03X126174Y643367I-3501J0D01*
G02X126047Y643553I73J186D01*
G01Y656102D01*
G02X141732Y671787I15685J0D01*
G01X151274D01*
G02X151463Y671652I0J-200D01*
G01Y671651D01*
G03X153511Y669514I3315J1128D01*
G01X153565Y669493D01*
X153634Y669401D01*
X153668Y668986D01*
G02X153570Y668797I-199J-17D01*
G03X151226Y664685I2435J-4112D01*
G03X152900Y661052I4779J0D01*
G02X152970Y660900I-130J-152D01*
G01Y660596D01*
G02X152900Y660444I-200J0D01*
G03Y653178I3105J-3633D01*
G02X152970Y653026I-130J-152D01*
G01Y652722D01*
G02X152900Y652570I-200J0D01*
G03Y645304I3105J-3633D01*
G02X152970Y645152I-130J-152D01*
G01Y644848D01*
G02X152900Y644696I-200J0D01*
G03Y637430I3105J-3633D01*
G02X152970Y637278I-130J-152D01*
G01Y636974D01*
G02X152900Y636822I-200J0D01*
G03Y629556I3105J-3633D01*
G02X152970Y629404I-130J-152D01*
G01Y629100D01*
G02X152900Y628948I-200J0D01*
G03Y621682I3105J-3633D01*
G02X152970Y621530I-130J-152D01*
G01Y621226D01*
G02X152900Y621074I-200J0D01*
G03Y613808I3105J-3633D01*
G02X152970Y613656I-130J-152D01*
G01Y613352D01*
G02X152900Y613200I-200J0D01*
G03Y605934I3105J-3633D01*
G02X152970Y605782I-130J-152D01*
G01Y605478D01*
G02X152900Y605326I-200J0D01*
G03X151226Y601693I3105J-3633D01*
G03X156004Y596914I4779J0D01*
G03X159637Y598589I-1J4779D01*
G02X159789Y598659I152J-130D01*
G01X160093D01*
G02X160245Y598589I0J-200D01*
G03X163878Y596914I3634J3104D01*
G03X168656Y601691I0J4778D01*
G01Y601693D01*
G03X166982Y605326I-4779J0D01*
G02X166912Y605478I130J152D01*
G01Y605782D01*
G02X166982Y605934I200J0D01*
G03Y613200I-3105J3633D01*
G02X166912Y613352I130J152D01*
G01Y613656D01*
G02X166982Y613808I200J0D01*
G03Y621074I-3105J3633D01*
G02X166912Y621226I130J152D01*
G01Y621530D01*
G02X166982Y621682I200J0D01*
G03Y628948I-3105J3633D01*
G02X166912Y629100I130J152D01*
G01Y629404D01*
G02X166982Y629556I200J0D01*
G03Y636822I-3105J3633D01*
G02X166912Y636974I130J152D01*
G01Y637278D01*
G02X166982Y637430I200J0D01*
G03Y644696I-3105J3633D01*
G02X166912Y644848I130J152D01*
G01Y645152D01*
G02X166982Y645304I200J0D01*
G03Y652570I-3105J3633D01*
G02X166912Y652722I130J152D01*
G01Y653026D01*
G02X166982Y653178I200J0D01*
G03Y660444I-3105J3633D01*
G02X166912Y660596I130J152D01*
G01Y660900D01*
G02X166982Y661052I200J0D01*
G03X168656Y664685I-3105J3633D01*
G03X163878Y669464I-4779J0D01*
G03X160245Y667789I1J-4779D01*
G02X160093Y667719I-152J130D01*
G01X159789D01*
G02X159637Y667789I0J200D01*
G03X157111Y669334I-3634J-3103D01*
G01X156962Y669485D01*
X156884Y669836D01*
G02X156955Y670036I195J43D01*
G03X158093Y671651I-2177J2743D01*
G01Y671652D01*
G02X158282Y671787I189J-65D01*
G01X171274D01*
G02X171463Y671652I0J-200D01*
G01Y671651D01*
G03X178093I3315J1127D01*
G01Y671652D01*
G02X178282Y671787I189J-65D01*
G01X191274D01*
G02X191463Y671652I0J-200D01*
G01Y671651D01*
G03X192451Y670162I3315J1128D01*
G01X192498Y670120D01*
X192527Y669999D01*
X192369Y669591D01*
G02X192178Y669463I-187J72D01*
G01X192177D01*
G03X192127Y669464I-121J-4777D01*
G01X192125D01*
G03X187348Y664687I1J-4778D01*
G01Y664685D01*
G03X189022Y661052I4779J0D01*
G02X189092Y660900I-130J-152D01*
G01Y660596D01*
G02X189022Y660444I-200J0D01*
G03Y653178I3105J-3633D01*
G02X189092Y653026I-130J-152D01*
G01Y652722D01*
G02X189022Y652570I-200J0D01*
G03X187348Y648937I3105J-3633D01*
G03X192126Y644158I4779J0D01*
G03X195759Y645833I-1J4779D01*
G02X195911Y645903I152J-130D01*
G01X196215D01*
G02X196367Y645833I0J-200D01*
G03X200000Y644158I3634J3104D01*
G03X204778Y648935I0J4778D01*
G01Y648937D01*
G03X203104Y652570I-4779J0D01*
G02X203034Y652722I130J152D01*
G01Y653026D01*
G02X203104Y653178I200J0D01*
G03Y660444I-3105J3633D01*
G02X203034Y660596I130J152D01*
G01Y660900D01*
G02X203104Y661052I200J0D01*
G03X204778Y664685I-3105J3633D01*
G03X200000Y669464I-4779J0D01*
G03X196367Y667789I1J-4779D01*
G02X196215Y667719I-152J130D01*
G01X195911D01*
G02X195759Y667789I0J200D01*
G03X194910Y668569I-3634J-3103D01*
G02X194833Y668784I116J163D01*
G01X194947Y669206D01*
X195043Y669286D01*
X195105Y669292D01*
G03X198093Y671651I-327J3487D01*
G01Y671652D01*
G02X198282Y671787I189J-65D01*
G01X211274D01*
G02X211463Y671652I0J-200D01*
G01Y671651D01*
G03X213377Y669569I3316J1127D01*
G01X213378D01*
G02X213497Y669395I-81J-183D01*
G01X213518Y668981D01*
X213462Y668881D01*
X213413Y668854D01*
G03X210970Y664685I2336J-4169D01*
G03X212644Y661052I4779J0D01*
G02X212714Y660900I-130J-152D01*
G01Y660596D01*
G02X212644Y660444I-200J0D01*
G03Y653178I3105J-3633D01*
G02X212714Y653026I-130J-152D01*
G01Y652722D01*
G02X212644Y652570I-200J0D01*
G03X210970Y648937I3105J-3633D01*
G03X215748Y644158I4779J0D01*
G03X219381Y645833I-1J4779D01*
G02X219533Y645903I152J-130D01*
G01X219837D01*
G02X219989Y645833I0J-200D01*
G03X223622Y644158I3634J3104D01*
G03X228400Y648935I0J4778D01*
G01Y648937D01*
G03X226726Y652570I-4779J0D01*
G02X226656Y652722I130J152D01*
G01Y653026D01*
G02X226726Y653178I200J0D01*
G03Y660444I-3105J3633D01*
G02X226656Y660596I130J152D01*
G01Y660900D01*
G02X226726Y661052I200J0D01*
G03X228400Y664685I-3105J3633D01*
G03X223622Y669464I-4779J0D01*
G03X219989Y667789I1J-4779D01*
G02X219837Y667719I-152J130D01*
G01X219533D01*
G02X219381Y667789I0J200D01*
G03X217032Y669288I-3633J-3104D01*
G01X216978Y669303D01*
X216900Y669387D01*
X216812Y669850D01*
X216852Y669956D01*
X216898Y669991D01*
G03X218093Y671651I-2121J2787D01*
G01Y671652D01*
G02X218282Y671787I189J-65D01*
G01X231274D01*
G02X231463Y671652I0J-200D01*
G01Y671651D01*
G03X238093I3315J1127D01*
G01Y671652D01*
G02X238282Y671787I189J-65D01*
G01X251274D01*
G02X251463Y671652I0J-200D01*
G01Y671651D01*
G03X253851Y669402I3315J1128D01*
G02X253998Y669208I-53J-193D01*
G01Y669194D01*
G02X253883Y669013I-200J0D01*
G03X252273Y667789I2021J-4330D01*
G02X252121Y667719I-152J130D01*
G01X251817D01*
G02X251665Y667789I0J200D01*
G03X248032Y669464I-3634J-3104D01*
G03X243254Y664687I0J-4778D01*
G01Y664685D01*
G03X244928Y661052I4779J0D01*
G02X244998Y660900I-130J-152D01*
G01Y660596D01*
G02X244928Y660444I-200J0D01*
G03Y653178I3105J-3633D01*
G02X244998Y653026I-130J-152D01*
G01Y652722D01*
G02X244928Y652570I-200J0D01*
G03X243254Y648937I3105J-3633D01*
G03X248032Y644158I4779J0D01*
G03X251665Y645833I-1J4779D01*
G02X251817Y645903I152J-130D01*
G01X252121D01*
G02X252273Y645833I0J-200D01*
G03X255906Y644158I3634J3104D01*
G03X260684Y648935I0J4778D01*
G01Y648937D01*
G03X259010Y652570I-4779J0D01*
G02X258940Y652722I130J152D01*
G01Y653026D01*
G02X259010Y653178I200J0D01*
G03X260222Y654759I-3103J3634D01*
G02X260345Y654865I181J-86D01*
G01X260627Y654950D01*
G02X260787Y654931I58J-191D01*
G03X266773I2993J5030D01*
G02X266933Y654950I102J-172D01*
G01X267215Y654865D01*
G02X267338Y654759I-58J-192D01*
G03X268550Y653178I4315J2053D01*
G02X268620Y653026I-130J-152D01*
G01Y652722D01*
G02X268550Y652570I-200J0D01*
G03X266876Y648937I3105J-3633D01*
G03X271654Y644158I4779J0D01*
G03X275287Y645833I-1J4779D01*
G02X275439Y645903I152J-130D01*
G01X275743D01*
G02X275895Y645833I0J-200D01*
G03X279528Y644158I3634J3104D01*
G03X284306Y648935I0J4778D01*
G01Y648937D01*
G03X282632Y652570I-4779J0D01*
G02X282562Y652722I130J152D01*
G01Y653026D01*
G02X282632Y653178I200J0D01*
G03Y660444I-3105J3633D01*
G02X282562Y660596I130J152D01*
G01Y660900D01*
G02X282632Y661052I200J0D01*
G03X284306Y664685I-3105J3633D01*
G03X279528Y669464I-4779J0D01*
G03X275895Y667789I1J-4779D01*
G02X275743Y667719I-152J130D01*
G01X275439D01*
G02X275287Y667789I0J200D01*
G03X274100Y668790I-3633J-3104D01*
G02X274004Y668992I102J172D01*
G03X274014Y669061I-4724J720D01*
G01X274091Y669193D01*
X274186Y669266D01*
G02X274332Y669306I122J-158D01*
G01X274333D01*
G03X274778Y669277I450J3473D01*
G03X278093Y671651I0J3501D01*
G01Y671652D01*
G02X278282Y671787I189J-65D01*
G01X291274D01*
G02X291463Y671652I0J-200D01*
G01Y671651D01*
G03X293155Y669676I3315J1128D01*
G01X293206Y669649D01*
X293262Y669554D01*
X293258Y669140D01*
G02X293148Y668963I-200J2D01*
G01X293147D01*
G03X290498Y664685I2130J-4278D01*
G03X292172Y661052I4779J0D01*
G02X292242Y660900I-130J-152D01*
G01Y660596D01*
G02X292172Y660444I-200J0D01*
G03Y653178I3105J-3633D01*
G02X292242Y653026I-130J-152D01*
G01Y652722D01*
G02X292172Y652570I-200J0D01*
G03X290498Y648937I3105J-3633D01*
G03X295276Y644158I4779J0D01*
G03X298909Y645833I-1J4779D01*
G02X299061Y645903I152J-130D01*
G01X299365D01*
G02X299517Y645833I0J-200D01*
G03X303150Y644158I3634J3104D01*
G03X307928Y648935I0J4778D01*
G01Y648937D01*
G03X306254Y652570I-4779J0D01*
G02X306184Y652722I130J152D01*
G01Y653026D01*
G02X306254Y653178I200J0D01*
G03Y660444I-3105J3633D01*
G02X306184Y660596I130J152D01*
G01Y660900D01*
G02X306254Y661052I200J0D01*
G03X307899Y664153I-3104J3633D01*
G02X308054Y664326I199J-22D01*
G01X308424Y664408D01*
G02X308637Y664318I43J-195D01*
G02X310961Y656102I-13361J-8216D01*
G01Y654961D01*
X310887Y654858D01*
X310826Y654837D01*
G03Y648207I1130J-3315D01*
G01X310887Y648186D01*
X310961Y648083D01*
Y635039D01*
G03X326772Y619228I15811J0D01*
G01X327783D01*
X327890Y619146D01*
X327908Y619081D01*
G03X331285Y616506I3377J927D01*
G03X334207Y618078I0J3502D01*
G02X334447Y618154I167J-110D01*
G02X338990Y615416I-5709J-14610D01*
G02X339036Y615170I-130J-152D01*
G03X338617Y613510I3082J-1661D01*
G03X342119Y610008I3502J0D01*
G01X342120D01*
G03X342826Y610080I0J3502D01*
G01X342867Y610084D01*
G02X343049Y609966I0J-200D01*
G02X344425Y603543I-14309J-6424D01*
G01Y598523D01*
G02X344289Y598334I-200J0D01*
G03Y591700I1123J-3317D01*
G02X344425Y591511I-64J-189D01*
G01Y578523D01*
G02X344289Y578334I-200J0D01*
G03Y571700I1123J-3317D01*
G02X344425Y571511I-64J-189D01*
G01Y558523D01*
G02X344289Y558334I-200J0D01*
G03Y551700I1123J-3317D01*
G02X344425Y551511I-64J-189D01*
G01Y538523D01*
G02X344289Y538334I-200J0D01*
G03Y531700I1123J-3317D01*
G02X344425Y531511I-64J-189D01*
G01Y518523D01*
G02X344289Y518334I-200J0D01*
G03Y511700I1123J-3317D01*
G02X344425Y511511I-64J-189D01*
G01Y498523D01*
G02X344289Y498334I-200J0D01*
G03Y491700I1123J-3317D01*
G02X344425Y491511I-64J-189D01*
G01Y478523D01*
G02X344289Y478334I-200J0D01*
G03Y471700I1123J-3317D01*
G02X344425Y471511I-64J-189D01*
G01Y458523D01*
G02X344289Y458334I-200J0D01*
G03Y451700I1123J-3317D01*
G02X344425Y451511I-64J-189D01*
G01Y438523D01*
G02X344289Y438334I-200J0D01*
G03X341910Y435017I1123J-3317D01*
G03X344470Y431644I3502J0D01*
G01X344615Y431472D01*
G03X344646Y431196I33333J3604D01*
G03X344809Y429977I33308J3833D01*
G03X344912Y429343I33144J5059D01*
G03X346168Y424369I33040J5697D01*
G03X347521Y420968I31783J10674D01*
G02X347484Y420746I-182J-84D01*
G03X346522Y418335I2540J-2411D01*
G03X350024Y414833I3502J0D01*
G03X350947Y414957I-1J3503D01*
G02X351160Y414884I53J-193D01*
G03X352189Y413584I26795J20152D01*
G03X352448Y413276I25790J21424D01*
G01X352476Y413244D01*
X352499Y413217D01*
X352506Y413209D01*
X352507Y413208D01*
G03X354006Y411573I25449J21827D01*
G03X355266Y410353I23944J23469D01*
G03X358642Y407631I22688J24685D01*
G01X358727Y407468D01*
X358721Y407421D01*
G03X358625Y406608I3406J-814D01*
G03X362127Y403106I3502J0D01*
G03X364614Y404142I0J3503D01*
G02X364834Y404186I142J-140D01*
G03X365403Y403949I13175J30830D01*
G01X365405D01*
X365415Y403944D01*
X365417D01*
G03X366056Y403693I12577J31079D01*
G03X366584Y403498I11879J31353D01*
G03X367070Y403327I11371J31540D01*
G01X367084Y403322D01*
G03X367126Y403308I10623J31799D01*
G01X367134Y403305D01*
G03X368155Y402975I10821J31734D01*
G03X369032Y402720I9799J32064D01*
G03X371832Y402075I8919J32319D01*
G03X373832Y401766I6117J32965D01*
G03X376172Y401559I4123J33273D01*
G02X376352Y401422I-10J-200D01*
G03X379680Y399008I3328J1087D01*
G03X382994Y401377I0J3502D01*
G01X383015Y401438D01*
X383118Y401512D01*
X396242D01*
X396345Y401438D01*
X396366Y401377D01*
G03X402994I3314J1133D01*
G01X403015Y401438D01*
X403118Y401512D01*
X416242D01*
X416345Y401438D01*
X416366Y401377D01*
G03X422994I3314J1133D01*
G01X423015Y401438D01*
X423118Y401512D01*
X436242D01*
X436345Y401438D01*
X436366Y401377D01*
G03X442994I3314J1133D01*
G01X443015Y401438D01*
X443118Y401512D01*
X449396D01*
G02X449596Y401312I0J-200D01*
G01Y335150D01*
G03X451596Y333150I2000J0D01*
G01X487800D01*
G03X489214Y333736I0J1999D01*
G01X499819Y344341D01*
G02X499961Y344400I142J-141D01*
G01X523489D01*
G02X523631Y344341I0J-200D01*
G01X534236Y333736D01*
G03X535650Y333150I1414J1413D01*
G01X614840D01*
G02X615037Y332980I-1J-200D01*
G03X621963I3463J520D01*
G01X621974Y333054D01*
X622086Y333150D01*
X654659D01*
G02X654842Y333029I-1J-200D01*
G01X654988Y332692D01*
G02X655004Y332613I-184J-78D01*
G01X654950Y332476D01*
G03X653998Y330076I2550J-2400D01*
G01Y330075D01*
G03X654331Y328585I3503J1D01*
G02Y328415I-181J-85D01*
G03X653998Y326925I3170J-1491D01*
G03X656686Y323518I3503J0D01*
G01X656687D01*
G02X656836Y323364I-47J-195D01*
G01X656920Y322953D01*
X656879Y322844D01*
X656832Y322809D01*
G03X655422Y320000I2093J-2809D01*
G03X658923Y316498I3502J0D01*
G01X658925D01*
G03X660415Y316831I-1J3503D01*
G02X660585I85J-181D01*
G03X662075Y316498I1491J3170D01*
G03Y323502I0J3502D01*
G03X660585Y323169I1J-3503D01*
G01X660501Y323151D01*
X660415Y323170D01*
G03X659739Y323407I-1491J-3170D01*
G01X659590Y323562D01*
X659517Y323916D01*
G02X659594Y324116I196J39D01*
G03X661002Y326923I-2095J2807D01*
G01Y326925D01*
G03X660669Y328415I-3503J-1D01*
G02Y328585I181J85D01*
G03X661002Y330075I-3170J1491D01*
G01Y330076D01*
G03X660050Y332476I-3502J0D01*
G01X659996Y332613D01*
G02X660012Y332692I200J1D01*
G01X660158Y333029D01*
G02X660341Y333150I184J-79D01*
G01X727939D01*
G02X728081Y333091I0J-200D01*
G01X733441Y327731D01*
G02X733500Y327589I-141J-142D01*
G01Y314077D01*
G02X733366Y313888I-200J0D01*
G37*
G36*
G01X1652073Y303473D02*
G03X1652383Y303498I-5J2000D01*
G01X1652400Y303500D01*
X1859989D01*
G02X1860129Y303443I0J-200D01*
G01X1860130Y303442D01*
X1861341Y302231D01*
G02X1861343Y302229I-140J-142D01*
G02X1861400Y302089I-143J-140D01*
G01Y268911D01*
G02X1861341Y268769I-200J0D01*
G01X1860131Y267559D01*
X1860103Y267530D01*
X1860029Y267500D01*
X1842700D01*
G03X1841286Y266914I0J-1999D01*
G01X1837086Y262714D01*
G03X1836500Y261300I1413J-1414D01*
G01Y164011D01*
G02X1836441Y163869I-200J0D01*
G01X1812231Y139659D01*
X1812203Y139630D01*
X1812129Y139600D01*
X1783162D01*
G03X1781748Y139014I0J-1999D01*
G01X1775321Y132588D01*
X1775192Y132568D01*
X1775133Y132599D01*
G03X1773504Y133002I-1631J-3099D01*
G01X1773500D01*
G03X1769998Y129500I0J-3502D01*
G01Y129496D01*
G03X1770401Y127867I3502J2D01*
G01X1770432Y127808D01*
X1770412Y127679D01*
X1765512Y122779D01*
X1765397Y122754D01*
X1765341Y122775D01*
G03X1765157Y122839I-1242J-3275D01*
G01X1765118Y122852D01*
X1765057Y122904D01*
X1764913Y123195D01*
G02X1764895Y123317I179J89D01*
G01X1764901Y123354D01*
X1764906Y123370D01*
G03X1765102Y124523I-3306J1155D01*
G01Y124524D01*
G03X1758098I-3502J0D01*
G03X1760543Y121185I3502J0D01*
G01X1760582Y121172D01*
X1760643Y121120D01*
X1760787Y120829D01*
G02X1760805Y120707I-179J-89D01*
G01X1760799Y120670D01*
X1760794Y120654D01*
G03X1760598Y119501I3306J-1155D01*
G01Y119498D01*
G03X1760825Y118258I3502J0D01*
G01X1760846Y118203D01*
X1760823Y118091D01*
X1760782Y118048D01*
G02X1760779Y118045I-143J140D01*
G01X1760734Y118000D01*
G02X1760732Y117998I-142J140D01*
G01X1760679Y117946D01*
G02X1760539Y117889I-140J143D01*
G01X1760483D01*
X1760459Y117895D01*
G03X1759601Y118002I-859J-3395D01*
G01X1759600D01*
G03X1756098Y114500I0J-3502D01*
G01Y114499D01*
G03X1756211Y113618I3502J1D01*
G01X1756225Y113566D01*
X1756197Y113464D01*
X1712723Y69989D01*
X1712695Y69960D01*
X1712621Y69930D01*
X1686130D01*
G03X1684716Y69344I0J-1999D01*
G01X1662659Y47287D01*
G03X1662073Y45873I1413J-1414D01*
G01Y8236D01*
G02X1662057Y8157I-200J-1D01*
G01X1662011Y8052D01*
X1661983Y8024D01*
G03X1661952Y7993I2106J-2137D01*
G01X1658017Y4059D01*
X1657989Y4030D01*
X1657915Y4000D01*
X1651898D01*
X1651795Y4074D01*
X1651774Y4135D01*
G03X1645146I-3314J-1132D01*
G01X1645125Y4074D01*
X1645022Y4000D01*
X1631898D01*
X1631795Y4074D01*
X1631774Y4135D01*
G03X1625146I-3314J-1132D01*
G01X1625125Y4074D01*
X1625022Y4000D01*
X1611898D01*
X1611795Y4074D01*
X1611774Y4135D01*
G03X1605146I-3314J-1132D01*
G01X1605125Y4074D01*
X1605022Y4000D01*
X1591898D01*
X1591795Y4074D01*
X1591774Y4135D01*
G03X1585146I-3314J-1132D01*
G01X1585125Y4074D01*
X1585022Y4000D01*
X1571898D01*
X1571795Y4074D01*
X1571774Y4135D01*
G03X1565146I-3314J-1132D01*
G01X1565125Y4074D01*
X1565022Y4000D01*
X1551898D01*
X1551795Y4074D01*
X1551774Y4135D01*
G03X1545146I-3314J-1132D01*
G01X1545125Y4074D01*
X1545022Y4000D01*
X1531898D01*
X1531795Y4074D01*
X1531774Y4135D01*
G03X1525146I-3314J-1132D01*
G01X1525125Y4074D01*
X1525022Y4000D01*
X1511898D01*
X1511795Y4074D01*
X1511774Y4135D01*
G03X1505146I-3314J-1132D01*
G01X1505125Y4074D01*
X1505022Y4000D01*
X1496657D01*
G02X1496489Y4092I0J200D01*
G01X1496462Y4134D01*
X1496454Y4236D01*
X1496498Y4332D01*
X1496523Y4365D01*
X1496539Y4379D01*
G03X1499168Y10197I-5123J5818D01*
G03X1491417Y17948I-7751J0D01*
G03X1485242Y14883I0J-7753D01*
G01X1485210Y14840D01*
X1485114Y14799D01*
X1484665Y14851D01*
X1484581Y14912D01*
X1484559Y14962D01*
G03X1480257Y17790I-4362J-1949D01*
G01X1480217D01*
X1480146Y17820D01*
X1480095Y17871D01*
G02Y18153I142J141D01*
G01X1480146Y18204D01*
X1480217Y18234D01*
X1480257D01*
G03X1475418Y23071I-60J4779D01*
G01Y23031D01*
X1475388Y22960D01*
X1475218Y22790D01*
X1475176D01*
X1475006Y22960D01*
X1474976Y23031D01*
Y23071D01*
G03X1465418I-4779J-59D01*
G01Y23031D01*
X1465388Y22960D01*
X1465248Y22820D01*
X1465177Y22790D01*
X1465137D01*
G03Y13234I60J-4778D01*
G01X1465177D01*
X1465248Y13204D01*
X1465299Y13153D01*
G02Y12871I-142J-141D01*
G01X1465248Y12820D01*
X1465177Y12790D01*
X1465137D01*
G03X1460418Y8012I60J-4779D01*
G03X1461773Y4679I4779J1D01*
G01X1461815Y4636D01*
X1461837Y4518D01*
X1461671Y4123D01*
G02X1461586Y4026I-185J76D01*
G01X1461539Y4000D01*
X306106D01*
G02X305938Y4092I0J200D01*
G01X305911Y4134D01*
X305903Y4236D01*
X305947Y4332D01*
X305972Y4365D01*
X305988Y4379D01*
G03X308617Y10197I-5123J5818D01*
G03X300866Y17948I-7751J0D01*
G03X294691Y14883I0J-7753D01*
G01X294659Y14840D01*
X294563Y14799D01*
X294114Y14851D01*
X294030Y14912D01*
X294008Y14962D01*
G03X289706Y17790I-4362J-1949D01*
G01X289666D01*
X289595Y17820D01*
X289424Y17991D01*
Y18033D01*
X289595Y18204D01*
X289666Y18234D01*
X289706D01*
G03X294424Y23012I-60J4778D01*
G03X289646Y27790I-4778J0D01*
G03X284868Y23072I0J-4778D01*
G01Y23032D01*
X284838Y22961D01*
X284667Y22790D01*
X284625D01*
X284454Y22961D01*
X284424Y23032D01*
Y23072D01*
G03X274868I-4778J-60D01*
G01Y23032D01*
X274838Y22961D01*
X274697Y22820D01*
X274626Y22790D01*
X274586D01*
G03Y13234I60J-4778D01*
G01X274626D01*
X274697Y13204D01*
X274868Y13033D01*
Y12991D01*
X274697Y12820D01*
X274626Y12790D01*
X274586D01*
G03X269868Y8012I60J-4778D01*
G03X271222Y4679I4779J0D01*
G01X271264Y4636D01*
X271286Y4518D01*
X271120Y4123D01*
G02X271035Y4026I-185J76D01*
G01X270988Y4000D01*
X236497D01*
G02X236355Y4059I0J200D01*
G01X233620Y6794D01*
X233591Y6822D01*
X233561Y6896D01*
Y11942D01*
G02X233875Y12106I200J0D01*
G02X233940Y12031I-114J-165D01*
G03X240866Y7760I6926J3480D01*
G03X248618Y15512I0J7752D01*
G03X248580Y16283I-7752J4D01*
G01X248576Y16314D01*
X248583Y16346D01*
G02X248822Y16498I195J-43D01*
G01X248862Y16489D01*
X248881Y16480D01*
G03X250866Y16048I1986J4347D01*
G03X246162Y21662I0J4778D01*
G01X246156Y21628D01*
X246121Y21568D01*
X245989Y21456D01*
X245845Y21455D01*
X245789Y21501D01*
G03X240866Y23264I-4923J-5992D01*
G03X233940Y18993I0J-7751D01*
G02X233875Y18918I-179J90D01*
G02X233561Y19082I-114J164D01*
G01Y71799D01*
G02X233604Y71923I200J0D01*
G01X233626Y71951D01*
X233682Y71986D01*
X233715Y71994D01*
G03X240851Y81000I-2115J9006D01*
G03X237128Y88418I-9252J0D01*
G01X237108Y88432D01*
X237080Y88467D01*
X237055Y88515D01*
G02X237144Y88784I179J90D01*
G01X237190Y88807D01*
X237242Y88805D01*
G03X237391Y88802I145J3500D01*
G03X240894Y92305I0J3503D01*
G03X240513Y93893I-3503J-1D01*
G01X240493Y93932D01*
X240490Y94004D01*
X240502Y94056D01*
X240516Y94081D01*
G03X240956Y95780I-3063J1700D01*
G03X240420Y97641I-3503J-1D01*
G01X240406Y97663D01*
X240391Y97709D01*
X240388Y97763D01*
X240399Y97818D01*
X240413Y97843D01*
G03X240832Y99503I-3084J1661D01*
G03X240303Y101352I-3503J-2D01*
G01X240288Y101376D01*
X240273Y101430D01*
Y101486D01*
X240288Y101540D01*
X240303Y101564D01*
G03X240832Y103412I-2973J1851D01*
G03X237331Y106914I-3502J0D01*
G01X237329D01*
G03X235437Y106359I0J-3502D01*
G02X235331Y106327I-109J168D01*
G02X235221Y106359I-1J200D01*
G03X233738Y106891I-1894J-2946D01*
G01X233737D01*
G02X233561Y107090I24J199D01*
G01Y129365D01*
G03X233560Y129447I-3000J4D01*
G01X233559Y129488D01*
X233574Y129526D01*
G02X233619Y129595I186J-72D01*
G01X233965Y129941D01*
G02X233967Y129943I142J-140D01*
G02X234107Y130000I140J-143D01*
G01X288489D01*
G02X288629Y129943I0J-200D01*
G01X288630Y129942D01*
X376005Y42566D01*
G02X376029Y42538I-139J-144D01*
G01Y42537D01*
G02X376043Y42335I-165J-113D01*
G01X375845Y41938D01*
X375732Y41878D01*
X375668Y41887D01*
G03X375192Y41920I-480J-3470D01*
G03X373773Y41619I2J-3503D01*
G01X373734Y41602D01*
X373650D01*
X373611Y41619D01*
G03X372192Y41920I-1421J-3202D01*
G03X370773Y41619I2J-3503D01*
G01X370734Y41602D01*
X370650D01*
X370611Y41619D01*
G03X369192Y41920I-1421J-3202D01*
G03Y34914I0J-3503D01*
G03X370611Y35215I-2J3503D01*
G01X370650Y35232D01*
X370734D01*
X370773Y35215D01*
G03X372192Y34914I1421J3202D01*
G03X373611Y35215I-2J3503D01*
G01X373650Y35232D01*
X373734D01*
X373773Y35215D01*
G03X375192Y34914I1421J3202D01*
G03X376611Y35215I-2J3503D01*
G01X376650Y35232D01*
X376734D01*
X376773Y35215D01*
G03X378192Y34914I1421J3202D01*
G03X381215Y36648I0J3502D01*
G01X381239Y36689D01*
X381315Y36739D01*
X381676Y36785D01*
G02X381843Y36728I26J-198D01*
G01X385553Y33019D01*
G03X386967Y32433I1414J1413D01*
G01X500610D01*
X500636Y32426D01*
G03X501678I521J1930D01*
G01X501704Y32433D01*
X635242D01*
X635268Y32426D01*
G03X636310I521J1930D01*
G01X636336Y32433D01*
X859631D01*
G02X859651Y32432I0J-200D01*
G02X859804Y32333I-20J-199D01*
G02X859813Y32317I-169J-106D01*
G01X859990Y31933D01*
X859974Y31818D01*
X859936Y31773D01*
G03X859098Y29500I2664J-2273D01*
G03X862600Y25998I3502J0D01*
G01X862602D01*
G03X863849Y26228I-1J3502D01*
G01X863891Y26244D01*
X863978Y26238D01*
X864099Y26171D01*
X864134Y26137D01*
X864147Y26116D01*
G03X867100Y24498I2953J1886D01*
G03X870158Y26292I0J3503D01*
G01X870178Y26327D01*
X870242Y26377D01*
X870452Y26432D01*
G02X870503Y26439I52J-193D01*
G01X870687D01*
X870737Y26425D01*
X870761Y26411D01*
G03X872533Y25930I1771J3020D01*
G03X876036Y29432I0J3503D01*
G03X875168Y31739I-3503J-1D01*
G01X875144Y31766D01*
X875114Y31845D01*
G02X875118Y31997I187J71D01*
G01X875260Y32314D01*
G02X875334Y32401I183J-81D01*
G01X875384Y32433D01*
X1004689D01*
G02X1004808Y32394I0J-200D01*
G03X1007192I1192J1607D01*
G02X1007311Y32433I119J-161D01*
G01X1010689D01*
G02X1010808Y32394I0J-200D01*
G03X1012000Y32000I1192J1606D01*
G01X1272214D01*
G03X1273628Y32586I0J1999D01*
G01X1278634Y37591D01*
X1278676Y37606D01*
G03X1279883Y38813I-676J1883D01*
G01X1279898Y38855D01*
X1300383Y59341D01*
G02X1300385Y59343I142J-140D01*
G02X1300525Y59400I140J-143D01*
G01X1393300D01*
G03X1394714Y59986I0J1999D01*
G01X1458669Y123941D01*
G02X1458671Y123943I142J-140D01*
G02X1458811Y124000I140J-143D01*
G01X1533702D01*
G03X1535116Y124586I0J1999D01*
G01X1584514Y173984D01*
G03X1585100Y175398I-1413J1414D01*
G01Y290589D01*
G02X1585157Y290729I200J0D01*
G01X1585158Y290730D01*
X1597869Y303441D01*
G02X1597871Y303443I142J-140D01*
G02X1598011Y303500I140J-143D01*
G01X1651746D01*
X1651763Y303498D01*
G03X1652073Y303473I315J1975D01*
G37*
G36*
G01X1099586Y62153D02*
X1114153Y47586D01*
G03X1115567Y47000I1414J1413D01*
G01X1275500D01*
G03X1275581Y47002I-9J2000D01*
G02X1275728Y46947I9J-200D01*
G01X1275938Y46747D01*
G02X1276000Y46603I-138J-145D01*
G01Y40696D01*
G02X1275985Y40621I-200J1D01*
G01X1275970Y40583D01*
X1275941Y40555D01*
X1271445Y36059D01*
G02X1271423Y36040I-141J141D01*
G02X1271303Y36000I-120J160D01*
G01X1018877D01*
G02X1018759Y36039I1J200D01*
G03X1017567Y36433I-1192J-1606D01*
G01X485800D01*
G02X485600Y36633I0J200D01*
G01Y46602D01*
G02X485662Y46747I200J0D01*
G01X485872Y46948D01*
G02X485940Y46990I137J-146D01*
G01X485977Y47004D01*
X486019Y47002D01*
G03X486100Y47000I90J1998D01*
G01X618033D01*
G03X619447Y47586I0J1999D01*
G01X634014Y62153D01*
G03X634600Y63567I-1413J1414D01*
G01Y106106D01*
G02X634640Y106226I200J0D01*
G02X634659Y106248I160J-119D01*
G01X638352Y109941D01*
G02X638374Y109960I141J-141D01*
G02X638494Y110000I120J-160D01*
G01X823600D01*
G03X825014Y110586I0J1999D01*
G01X832014Y117586D01*
G03X832600Y119000I-1413J1414D01*
G01Y185000D01*
G03X832014Y186414I-1999J0D01*
G01X828514Y189914D01*
G03X827100Y190500I-1414J-1413D01*
G01X778729D01*
G03X777315Y189914I0J-1999D01*
G01X754142Y166741D01*
G02X754120Y166722I-141J141D01*
G02X754000Y166682I-120J160D01*
G01X748875D01*
G02X748848Y166684I1J200D01*
G02X748685Y166819I27J198D01*
G01X748565Y167179D01*
G02X748560Y167198I191J60D01*
G02X748635Y167402I195J44D01*
G03X748847Y167586I-1201J1598D01*
G01X763526Y182265D01*
G03X764112Y183679I-1413J1414D01*
G01Y200875D01*
G03X763526Y202289I-1999J0D01*
G01X761381Y204434D01*
G03X759967Y205020I-1414J-1413D01*
G01X719746D01*
G03X718332Y204434I0J-1999D01*
G01X715686Y201788D01*
G03X715100Y200374I1413J-1414D01*
G01Y183500D01*
G03X715686Y182086I1999J0D01*
G01X730186Y167586D01*
G03X730398Y167402I1413J1414D01*
G02X730473Y167199I-120J-160D01*
G02X730468Y167179I-196J38D01*
G01X730348Y166819D01*
G02X730158Y166682I-190J63D01*
G01X685618D01*
G02X685543Y166697I1J200D01*
G01X685505Y166712D01*
X685477Y166741D01*
X679912Y172306D01*
G02X679893Y172328I141J141D01*
G02X679853Y172448I160J120D01*
G01Y198682D01*
G02X679893Y198802I200J0D01*
G02X679912Y198824I160J-119D01*
G01X680231Y199143D01*
G02X680253Y199162I141J-141D01*
G02X680373Y199202I120J-160D01*
G01X684962D01*
G03X686376Y199788I0J1999D01*
G01X695517Y208929D01*
G03X696103Y210343I-1413J1414D01*
G01Y215272D01*
G03X695517Y216686I-1999J0D01*
G01X692797Y219406D01*
G03X691383Y219992I-1414J-1413D01*
G01X633245D01*
G02X633170Y220007I1J200D01*
G01X633132Y220022D01*
X633104Y220051D01*
X602878Y250277D01*
G02X602859Y250299I141J141D01*
G02X602819Y250419I160J120D01*
G01Y296027D01*
G02X602859Y296147I200J0D01*
G02X602878Y296169I160J-119D01*
G01X604650Y297941D01*
G02X604672Y297960I141J-141D01*
G02X604792Y298000I120J-160D01*
G01X648589D01*
G02X648621Y297997I-3J-200D01*
G01X648623D01*
G02X648729Y297943I-34J-197D01*
G01X649941Y296731D01*
G02X649960Y296709I-141J-141D01*
G02X650000Y296589I-160J-120D01*
G01Y267133D01*
G02X649987Y267063I-200J1D01*
G01X649953Y266971D01*
X649932Y266945D01*
G03Y265055I1169J-945D01*
G01X649953Y265029D01*
X649988Y264936D01*
G02X650000Y264866I-188J-68D01*
G01Y253175D01*
Y253162D01*
G02X649836Y252978I-200J13D01*
G01X649835D01*
G03Y250022I264J-1478D01*
G01X649836D01*
G02X650000Y249838I-36J-197D01*
G01Y236000D01*
G03X650586Y234586I1999J0D01*
G01X652687Y232485D01*
G03X654101Y231899I1414J1413D01*
G01X667628D01*
G03X669042Y232485I0J1999D01*
G01X671813Y235256D01*
G03X672399Y236670I-1413J1414D01*
G01Y266978D01*
G03X671813Y268392I-1999J0D01*
G01X663559Y276646D01*
G02X663540Y276668I141J141D01*
G02X663500Y276788I160J120D01*
G01Y279726D01*
G02X663522Y279817I200J0D01*
G03X663686Y280499I-1338J682D01*
G01Y280501D01*
G03X663522Y281182I-1502J-1D01*
G01Y281183D01*
X663521Y281185D01*
G02X663500Y281274I179J89D01*
G01Y283726D01*
G02X663522Y283817I200J0D01*
G03X663686Y284499I-1338J682D01*
G01Y284501D01*
G03X663522Y285182I-1502J-1D01*
G01Y285183D01*
X663521Y285185D01*
G02X663500Y285274I179J89D01*
G01Y287726D01*
G02X663522Y287817I200J0D01*
G03X663686Y288499I-1338J682D01*
G01Y288501D01*
G03X663522Y289182I-1502J-1D01*
G01Y289183D01*
X663521Y289185D01*
G02X663500Y289274I179J89D01*
G01Y297089D01*
G02X663540Y297209I200J0D01*
G02X663559Y297231I160J-119D01*
G01X664507Y298179D01*
G02X664529Y298198I141J-141D01*
G02X664649Y298238I120J-160D01*
G01X719300D01*
G02X719500Y298038I0J-200D01*
G01Y282757D01*
Y282747D01*
G02X719463Y282640I-200J9D01*
G02X719445Y282619I-161J119D01*
G01X719364Y282534D01*
G02X719304Y282491I-145J138D01*
G01X719272Y282476D01*
X719234Y282473D01*
G03X715982Y278980I250J-3493D01*
G01Y278977D01*
G03X716426Y277272I3502J2D01*
G01X716437Y277252D01*
X716450Y277211D01*
X716451Y277189D01*
G02X716439Y277105I-200J-14D01*
G01X716331Y276817D01*
G02X716284Y276745I-187J71D01*
G01X716253Y276715D01*
X716211Y276700D01*
G03X713882Y273400I1173J-3300D01*
G03X717384Y269898I3502J0D01*
G01X717387D01*
G03X718905Y270244I0J3503D01*
G01X718925Y270254D01*
X718975Y270265D01*
G02X719124Y270240I44J-195D01*
G01X719405Y270065D01*
G02X719500Y269895I-105J-170D01*
G01Y268000D01*
G03X720086Y266586I1999J0D01*
G01X722586Y264086D01*
G03X724000Y263500I1414J1413D01*
G01X731500D01*
G03X732914Y264086I0J1999D01*
G01X736914Y268086D01*
G03X737500Y269500I-1413J1414D01*
G01Y305563D01*
G02X737527Y305663I200J0D01*
G03X738002Y307423I-3027J1761D01*
G01Y307425D01*
G03X737669Y308915I-3503J-1D01*
G02Y309085I181J85D01*
G03X738002Y310575I-3170J1491D01*
G01Y310577D01*
G03X737527Y312337I-3502J-1D01*
G02X737500Y312437I173J100D01*
G01Y328500D01*
G03X736914Y329914I-1999J0D01*
G01X730264Y336564D01*
G03X728850Y337150I-1414J-1413D01*
G01X635841D01*
G02X635700Y337208I0J200D01*
G02X635677Y337236I143J141D01*
G01X635490Y337505D01*
G02X635456Y337595I165J114D01*
G01X635450Y337643D01*
X635467Y337689D01*
G03X635688Y338912I-3282J1224D01*
G01Y338917D01*
G03X628684I-3502J0D01*
G01Y338912D01*
G03X628905Y337689I3503J1D01*
G02X628916Y337595I-187J-70D01*
G01X628910Y337546D01*
X628695Y337236D01*
G02X628672Y337208I-166J113D01*
G02X628531Y337150I-141J142D01*
G01X536560D01*
G02X536485Y337165I1J200D01*
G01X536447Y337180D01*
X536419Y337209D01*
X525814Y347814D01*
G03X524400Y348400I-1414J-1413D01*
G01X499050D01*
G03X497636Y347814I0J-1999D01*
G01X487031Y337209D01*
G02X487009Y337190I-141J141D01*
G02X486889Y337150I-120J160D01*
G01X453796D01*
G02X453596Y337350I0J200D01*
G01Y401312D01*
G02X453796Y401512I200J0D01*
G01X458472D01*
G02X458614Y401453I0J-200D01*
G03X460746I1066J1056D01*
G02X460888Y401512I142J-141D01*
G01X478472D01*
G02X478614Y401453I0J-200D01*
G03X480746I1066J1056D01*
G02X480888Y401512I142J-141D01*
G01X498472D01*
G02X498614Y401453I0J-200D01*
G03X500746I1066J1056D01*
G02X500888Y401512I142J-141D01*
G01X518472D01*
G02X518614Y401453I0J-200D01*
G03X520746I1066J1056D01*
G02X520888Y401512I142J-141D01*
G01X538472D01*
G02X538614Y401453I0J-200D01*
G03X540746I1066J1056D01*
G02X540888Y401512I142J-141D01*
G01X558472D01*
G02X558614Y401453I0J-200D01*
G03X560746I1066J1056D01*
G02X560888Y401512I142J-141D01*
G01X578472D01*
G02X578614Y401453I0J-200D01*
G03X580746I1066J1056D01*
G02X580888Y401512I142J-141D01*
G01X598472D01*
G02X598614Y401453I0J-200D01*
G03X600746I1066J1056D01*
G02X600888Y401512I142J-141D01*
G01X618472D01*
G02X618614Y401453I0J-200D01*
G03X620746I1066J1056D01*
G02X620888Y401512I142J-141D01*
G01X638472D01*
G02X638614Y401453I0J-200D01*
G03X640746I1066J1056D01*
G02X640888Y401512I142J-141D01*
G01X658472D01*
G02X658614Y401453I0J-200D01*
G03X660746I1066J1056D01*
G02X660888Y401512I142J-141D01*
G01X678472D01*
G02X678614Y401453I0J-200D01*
G03X680746I1066J1056D01*
G02X680888Y401512I142J-141D01*
G01X698472D01*
G02X698614Y401453I0J-200D01*
G03X700746I1066J1056D01*
G02X700888Y401512I142J-141D01*
G01X718472D01*
G02X718614Y401453I0J-200D01*
G03X720746I1066J1056D01*
G02X720888Y401512I142J-141D01*
G01X738472D01*
G02X738614Y401453I0J-200D01*
G03X740746I1066J1056D01*
G02X740888Y401512I142J-141D01*
G01X758472D01*
G02X758614Y401453I0J-200D01*
G03X760746I1066J1056D01*
G02X760888Y401512I142J-141D01*
G01X778472D01*
G02X778614Y401453I0J-200D01*
G03X780746I1066J1056D01*
G02X780888Y401512I142J-141D01*
G01X798472D01*
G02X798614Y401453I0J-200D01*
G03X800746I1066J1056D01*
G02X800888Y401512I142J-141D01*
G01X818472D01*
G02X818614Y401453I0J-200D01*
G03X820746I1066J1056D01*
G02X820888Y401512I142J-141D01*
G01X838472D01*
G02X838614Y401453I0J-200D01*
G03X840746I1066J1056D01*
G02X840888Y401512I142J-141D01*
G01X858472D01*
G02X858614Y401453I0J-200D01*
G03X860746I1066J1056D01*
G02X860888Y401512I142J-141D01*
G01X878472D01*
G02X878614Y401453I0J-200D01*
G03X880746I1066J1056D01*
G02X880888Y401512I142J-141D01*
G01X898472D01*
G02X898614Y401453I0J-200D01*
G03X900746I1066J1056D01*
G02X900888Y401512I142J-141D01*
G01X918472D01*
G02X918614Y401453I0J-200D01*
G03X920746I1066J1056D01*
G02X920888Y401512I142J-141D01*
G01X938472D01*
G02X938614Y401453I0J-200D01*
G03X940746I1066J1056D01*
G02X940888Y401512I142J-141D01*
G01X958472D01*
G02X958614Y401453I0J-200D01*
G03X960746I1066J1056D01*
G02X960888Y401512I142J-141D01*
G01X978472D01*
G02X978614Y401453I0J-200D01*
G03X980746I1066J1056D01*
G02X980888Y401512I142J-141D01*
G01X998472D01*
G02X998614Y401453I0J-200D01*
G03X1000746I1066J1056D01*
G02X1000888Y401512I142J-141D01*
G01X1018472D01*
G02X1018614Y401453I0J-200D01*
G03X1020746I1066J1056D01*
G02X1020888Y401512I142J-141D01*
G01X1038472D01*
G02X1038614Y401453I0J-200D01*
G03X1040746I1066J1056D01*
G02X1040888Y401512I142J-141D01*
G01X1058472D01*
G02X1058614Y401453I0J-200D01*
G03X1060746I1066J1056D01*
G02X1060888Y401512I142J-141D01*
G01X1078472D01*
G02X1078614Y401453I0J-200D01*
G03X1080746I1066J1056D01*
G02X1080888Y401512I142J-141D01*
G01X1098472D01*
G02X1098614Y401453I0J-200D01*
G03X1100746I1066J1056D01*
G02X1100888Y401512I142J-141D01*
G01X1118472D01*
G02X1118614Y401453I0J-200D01*
G03X1120746I1066J1056D01*
G02X1120888Y401512I142J-141D01*
G01X1138472D01*
G02X1138614Y401453I0J-200D01*
G03X1140746I1066J1056D01*
G02X1140888Y401512I142J-141D01*
G01X1158472D01*
G02X1158614Y401453I0J-200D01*
G03X1160746I1066J1056D01*
G02X1160888Y401512I142J-141D01*
G01X1178472D01*
G02X1178614Y401453I0J-200D01*
G03X1180746I1066J1056D01*
G02X1180888Y401512I142J-141D01*
G01X1198472D01*
G02X1198614Y401453I0J-200D01*
G03X1200746I1066J1056D01*
G02X1200888Y401512I142J-141D01*
G01X1218472D01*
G02X1218614Y401453I0J-200D01*
G03X1220746I1066J1056D01*
G02X1220888Y401512I142J-141D01*
G01X1238472D01*
G02X1238614Y401453I0J-200D01*
G03X1240746I1066J1056D01*
G02X1240888Y401512I142J-141D01*
G01X1258472D01*
G02X1258614Y401453I0J-200D01*
G03X1260746I1066J1056D01*
G02X1260888Y401512I142J-141D01*
G01X1278472D01*
G02X1278614Y401453I0J-200D01*
G03X1280746I1066J1056D01*
G02X1280888Y401512I142J-141D01*
G01X1293000D01*
G02X1293200Y401312I0J-200D01*
G01Y351189D01*
G02X1293000Y350989I-200J0D01*
G01X1180758D01*
G02X1180680Y351005I0J200D01*
G01X1180576Y351049D01*
X1180549Y351075D01*
G03X1178451I-1049J-1075D01*
G01X1178424Y351049D01*
X1178320Y351005D01*
G02X1178242Y350989I-78J184D01*
G01X1177258D01*
G02X1177180Y351005I0J200D01*
G01X1177076Y351049D01*
X1177049Y351075D01*
G03X1174951I-1049J-1075D01*
G01X1174924Y351049D01*
X1174820Y351005D01*
G02X1174742Y350989I-78J184D01*
G01X1172848D01*
G02X1172779Y351001I-1J200D01*
G01X1172715Y351025D01*
G02X1172657Y351058I69J188D01*
G03X1171701Y351402I-957J-1158D01*
G01X1171699D01*
G03X1170743Y351058I1J-1502D01*
G02X1170685Y351025I-127J155D01*
G01X1170621Y351001D01*
G02X1170552Y350989I-68J188D01*
G01X1169048D01*
G02X1168996Y350996I0J200D01*
G01X1168929Y351014D01*
X1168908Y351025D01*
X1168907D01*
G03X1167493I-707J-1325D01*
G01X1167492D01*
X1167471Y351014D01*
X1167404Y350996D01*
G02X1167352Y350989I-52J193D01*
G01X1038045D01*
G03X1036631Y350403I0J-1999D01*
G01X1024231Y338003D01*
G03X1023645Y336589I1413J-1414D01*
G01Y229565D01*
G03X1024231Y228151I1999J0D01*
G01X1029206Y223176D01*
G03X1030620Y222590I1414J1413D01*
G01X1073884D01*
G03X1075298Y223176I0J1999D01*
G01X1077880Y225758D01*
G03X1078466Y227172I-1413J1414D01*
G01Y247261D01*
G03X1077880Y248675I-1999J0D01*
G01X1061415Y265140D01*
G02X1061357Y265294I142J141D01*
G01X1061376Y265593D01*
G02X1061377Y265602I199J-18D01*
G02X1061399Y265674I199J-21D01*
G01X1061419Y265711D01*
X1061453Y265738D01*
X1061454Y265739D01*
G03X1062802Y268500I-2154J2761D01*
G03X1060523Y271781I-3501J0D01*
G02X1060393Y271968I70J187D01*
G01Y276132D01*
G02X1060523Y276319I200J0D01*
G03Y282881I-1223J3281D01*
G02X1060393Y283068I70J187D01*
G01Y283946D01*
G02X1060433Y284066I200J0D01*
G02X1060452Y284088I160J-119D01*
G01X1066089Y289725D01*
G02X1066111Y289744I141J-141D01*
G02X1066231Y289784I120J-160D01*
G01X1069445D01*
G02X1069559Y289748I0J-200D01*
G01X1069568Y289742D01*
X1069572Y289739D01*
G03X1071408I918J1187D01*
G01X1071412Y289742D01*
X1071421Y289748D01*
G02X1071535Y289784I114J-164D01*
G01X1196391D01*
X1196397D01*
G03X1196499Y289782I120J3500D01*
G01X1196501D01*
G03X1196603Y289784I-18J3502D01*
G01X1201391D01*
X1201397D01*
G03X1201499Y289782I120J3500D01*
G01X1201501D01*
G03X1201603Y289784I-18J3502D01*
G01X1221115D01*
G02X1221315Y289584I0J-200D01*
G01Y269642D01*
G02X1221300Y269567I-200J1D01*
G01X1221285Y269529D01*
X1221256Y269501D01*
X1218949Y267194D01*
G02X1218927Y267175I-141J141D01*
G02X1218807Y267135I-120J160D01*
G01X1213770D01*
G02X1213594Y267241I1J200D01*
G03X1207406I-3094J-1642D01*
G02X1207230Y267135I-177J94D01*
G01X1202707D01*
G02X1202582Y267179I0J200D01*
G02X1202512Y267289I125J157D01*
G01Y267290D01*
G03X1202198Y268132I-3411J-793D01*
G01X1202187Y268153D01*
X1202175Y268198D01*
G02Y268298I194J50D01*
G01X1202187Y268343D01*
X1202198Y268364D01*
G03X1202604Y270000I-3098J1637D01*
G01Y270002D01*
G03X1202201Y271632I-3503J-1D01*
G01X1202189Y271654D01*
X1202178Y271699D01*
X1202172Y271724D01*
Y271773D01*
X1202190Y271842D01*
X1202201Y271863D01*
G03X1202606Y273498I-3102J1636D01*
G01Y273500D01*
G03X1202191Y275154I-3506J-1D01*
G01X1202179Y275176D01*
X1202167Y275223D01*
Y275277D01*
X1202179Y275324D01*
X1202191Y275346D01*
G03X1202606Y277000I-3091J1655D01*
G03X1195594I-3506J0D01*
G03X1196009Y275346I3506J1D01*
G01X1196021Y275324D01*
X1196033Y275277D01*
Y275223D01*
X1196021Y275176D01*
X1196009Y275154D01*
G03X1195594Y273500I3091J-1655D01*
G01Y273498D01*
G03X1195999Y271863I3507J1D01*
G01X1196010Y271842D01*
X1196028Y271773D01*
Y271724D01*
X1196022Y271699D01*
X1196011Y271654D01*
X1195999Y271632D01*
G03X1195596Y270002I3100J-1631D01*
G01Y270000D01*
G03X1196002Y268364I3504J1D01*
G01X1196013Y268343D01*
X1196025Y268298D01*
G02Y268198I-194J-50D01*
G01X1196013Y268153D01*
X1196002Y268132D01*
G03X1195688Y267290I3097J-1635D01*
G01Y267289D01*
G02X1195618Y267179I-195J47D01*
G02X1195493Y267135I-125J156D01*
G01X1190970D01*
G02X1190794Y267241I1J200D01*
G03X1184606I-3094J-1642D01*
G02X1184430Y267135I-177J94D01*
G01X1175556D01*
G02X1175460Y267159I-1J200D01*
G01X1175439Y267171D01*
X1175403Y267204D01*
X1175389Y267226D01*
X1175206Y267506D01*
G02X1175191Y267695I168J108D01*
G01Y267696D01*
G03X1175488Y269105I-3206J1411D01*
G01Y269110D01*
G03X1174277Y271759I-3503J0D01*
G02X1174275Y271761I140J142D01*
G02X1174207Y271911I132J150D01*
G01Y272215D01*
G02X1174276Y272366I200J0D01*
G03X1175488Y275016I-2291J2650D01*
G03X1168484I-3502J0D01*
G03X1169696Y272366I3503J0D01*
G02X1169765Y272215I-131J-151D01*
G01Y271911D01*
G02X1169697Y271761I-200J0D01*
G01X1169696Y271760D01*
G03X1168484Y269110I2291J-2650D01*
G03X1171427Y265652I3503J0D01*
G01X1171428D01*
G02X1171527Y265606I-32J-198D01*
G01X1171547Y265589D01*
X1171577Y265544D01*
X1171695Y265177D01*
G02X1171646Y264974I-190J-61D01*
G01X1166086Y259414D01*
G03X1165500Y258000I1413J-1414D01*
G01Y244810D01*
G02X1165485Y244735I-200J1D01*
G01X1165470Y244697D01*
X1165441Y244669D01*
X1154331Y233559D01*
G02X1154309Y233540I-141J141D01*
G02X1154189Y233500I-120J160D01*
G01X1111400D01*
G03X1109986Y232914I0J-1999D01*
G01X1054231Y177159D01*
G02X1054209Y177140I-141J141D01*
G02X1054089Y177100I-120J160D01*
G01X1017800D01*
G03X1016386Y176514I0J-1999D01*
G01X1006693Y166821D01*
G02X1006671Y166802I-141J141D01*
G02X1006551Y166762I-120J160D01*
G01X1003542D01*
G02X1003355Y166893I1J200D01*
G01X1003235Y167220D01*
G02X1003223Y167281I188J69D01*
G02X1003225Y167319I200J9D01*
G02X1003242Y167375I198J-30D01*
G01X1003286Y167467D01*
X1003317Y167495D01*
G03X1003414Y167586I-1318J1503D01*
G01X1017914Y182086D01*
G03X1018500Y183500I-1413J1414D01*
G01Y200374D01*
G03X1017914Y201788I-1999J0D01*
G01X1015268Y204434D01*
G03X1013854Y205020I-1414J-1413D01*
G01X973633D01*
G03X972219Y204434I0J-1999D01*
G01X970074Y202289D01*
G03X969488Y200875I1413J-1414D01*
G01Y183679D01*
G03X970074Y182265I1999J0D01*
G01X984753Y167586D01*
G03X984850Y167495I1415J1412D01*
G01X984881Y167467D01*
X984925Y167375D01*
G02X984942Y167319I-181J-86D01*
G02X984944Y167281I-198J-29D01*
G02X984932Y167220I-200J8D01*
G01X984812Y166893D01*
G02X984625Y166762I-188J69D01*
G01X981199D01*
G02X981124Y166777I1J200D01*
G01X981086Y166792D01*
X981058Y166821D01*
X957965Y189914D01*
G03X956551Y190500I-1414J-1413D01*
G01X906500D01*
G03X905086Y189914I0J-1999D01*
G01X901586Y186414D01*
G03X901000Y185000I1413J-1414D01*
G01Y119000D01*
G03X901586Y117586I1999J0D01*
G01X908586Y110586D01*
G03X910000Y110000I1414J1413D01*
G01X1095106D01*
G02X1095138Y109997I-3J-200D01*
G01X1095140D01*
G02X1095246Y109943I-34J-197D01*
G01X1098941Y106248D01*
G02X1098960Y106226I-141J-141D01*
G02X1099000Y106106I-160J-120D01*
G01Y63567D01*
G03X1099586Y62153I1999J0D01*
G37*
G36*
G01X486511Y180500D02*
X555989D01*
G02X556131Y180441I0J-200D01*
G01X559541Y177031D01*
G02X559600Y176889I-141J-142D01*
G01Y164044D01*
G02X559495Y163867I-200J-1D01*
G03X557653Y160784I1659J-3083D01*
G03X557709Y160159I3502J-1D01*
G01X557718Y160110D01*
X557689Y160017D01*
X557131Y159459D01*
G02X556989Y159400I-142J141D01*
G01X547900D01*
G03X546486Y158814I0J-1999D01*
G01X542086Y154414D01*
G03X541500Y153000I1413J-1414D01*
G01Y133200D01*
G03X542086Y131786I1999J0D01*
G01X543266Y130606D01*
G03X544680Y130020I1414J1413D01*
G01X548774D01*
G02X548918Y129959I0J-200D01*
G03X551430Y128898I2511J2441D01*
G03X553942Y129959I1J3502D01*
G02X554086Y130020I144J-139D01*
G01X557169D01*
G02X557311Y129961I0J-200D01*
G01X559541Y127731D01*
G02X559600Y127589I-141J-142D01*
G01Y119290D01*
X559595Y119267D01*
G03X559504Y118477I3412J-793D01*
G03X559595Y117687I3503J3D01*
G01X559600Y117664D01*
Y114936D01*
X559595Y114913D01*
G03X559504Y114123I3412J-793D01*
G03X559595Y113333I3503J3D01*
G01X559600Y113310D01*
Y52911D01*
G02X559541Y52769I-200J0D01*
G01X557831Y51059D01*
G02X557689Y51000I-142J141D01*
G01X487011D01*
G02X486869Y51059I0J200D01*
G01X485659Y52269D01*
G02X485600Y52411I141J142D01*
G01Y179589D01*
G02X485659Y179731I200J0D01*
G01X486369Y180441D01*
G02X486511Y180500I142J-141D01*
G37*
G36*
G01X487011Y315000D02*
X535464D01*
G02X535606Y314941I0J-200D01*
G01X536786Y313761D01*
G02X536845Y313619I-141J-142D01*
G01Y268913D01*
G03X537431Y267499I1999J0D01*
G01X541325Y263605D01*
G03X542739Y263019I1414J1413D01*
G01X548986D01*
G02X549118Y262969I0J-200D01*
G03X551430Y262098I2311J2631D01*
G03X553742Y262969I1J3502D01*
G02X553874Y263019I132J-150D01*
G01X559400D01*
G02X559600Y262819I0J-200D01*
G01Y252490D01*
X559595Y252467D01*
G03X559504Y251677I3412J-793D01*
G03X559595Y250887I3503J3D01*
G01X559600Y250864D01*
Y248136D01*
X559595Y248113D01*
G03X559504Y247323I3412J-793D01*
G03X559595Y246533I3503J3D01*
G01X559600Y246510D01*
Y187911D01*
G02X559541Y187769I-200J0D01*
G01X556331Y184559D01*
G02X556189Y184500I-142J141D01*
G01X486511D01*
G02X486369Y184559I0J200D01*
G01X485659Y185269D01*
G02X485600Y185411I141J142D01*
G01Y313589D01*
G02X485659Y313731I200J0D01*
G01X486869Y314941D01*
G02X487011Y315000I142J-141D01*
G37*
G36*
G01X578911Y263019D02*
X584397D01*
G02X584539Y262960I0J-200D01*
G01X585282Y262217D01*
G02X585341Y262075I-141J-142D01*
G01Y234659D01*
G03X585927Y233245I1999J0D01*
G01X587486Y231686D01*
G03X588900Y231100I1414J1413D01*
G01X598584D01*
G03X599998Y231686I0J1999D01*
G01X602233Y233921D01*
G03X602819Y235335I-1413J1414D01*
G01Y244197D01*
G02X602942Y244382I200J0D01*
G01X602999Y244406D01*
X603117Y244382D01*
X630921Y216578D01*
G03X632335Y215992I1414J1413D01*
G01X690472D01*
G02X690614Y215933I0J-200D01*
G01X692044Y214503D01*
G02X692103Y214361I-141J-142D01*
G01Y211254D01*
G02X692044Y211112I-200J0D01*
G01X684193Y203261D01*
G02X684051Y203202I-142J141D01*
G01X679462D01*
G03X678048Y202616I0J-1999D01*
G01X676439Y201007D01*
G03X675853Y199593I1413J-1414D01*
G01Y171537D01*
G03X676439Y170123I1999J0D01*
G01X683294Y163268D01*
G03X684708Y162682I1414J1413D01*
G01X754911D01*
G03X756325Y163268I0J1999D01*
G01X779498Y186441D01*
G02X779640Y186500I142J-141D01*
G01X826189D01*
G02X826331Y186441I0J-200D01*
G01X828541Y184231D01*
G02X828600Y184089I-141J-142D01*
G01Y119911D01*
G02X828541Y119769I-200J0D01*
G01X822831Y114059D01*
G02X822689Y114000I-142J141D01*
G01X637583D01*
G03X636169Y113414I0J-1999D01*
G01X631186Y108431D01*
G03X630600Y107017I1413J-1414D01*
G01Y64478D01*
G02X630541Y64336I-200J0D01*
G01X617264Y51059D01*
G02X617122Y51000I-142J141D01*
G01X565511D01*
G02X565369Y51059I0J200D01*
G01X563659Y52769D01*
G02X563600Y52911I141J142D01*
G01Y110577D01*
X563688Y110687D01*
X563757Y110702D01*
G03X566510Y114123I-749J3421D01*
G03X565840Y116182I-3503J-1D01*
G02Y116418I162J118D01*
G03X566510Y118477I-2833J2060D01*
G03X563757Y121898I-3502J0D01*
G01X563688Y121913D01*
X563600Y122023D01*
Y127789D01*
G02X563659Y127931I200J0D01*
G01X565689Y129961D01*
G02X565831Y130020I142J-141D01*
G01X571574D01*
G02X571718Y129959I0J-200D01*
G03X574230Y128898I2511J2441D01*
G03X576742Y129959I1J3502D01*
G02X576886Y130020I144J-139D01*
G01X580120D01*
G03X581534Y130606I0J1999D01*
G01X583514Y132586D01*
G03X584100Y134000I-1413J1414D01*
G01Y151100D01*
G03X583514Y152514I-1999J0D01*
G01X577214Y158814D01*
G03X575800Y159400I-1414J-1413D01*
G01X568081D01*
G02X567923Y159478I0J200D01*
G01X567700Y159765D01*
X567682Y159855D01*
X567694Y159901D01*
G03X567807Y160784I-3389J882D01*
G03X564305Y164286I-3502J0D01*
G03X564031Y164275I3J-3502D01*
G01X563989Y164272D01*
X563911Y164299D01*
X563664Y164527D01*
G02X563600Y164674I136J147D01*
G01Y243777D01*
X563688Y243887D01*
X563757Y243902D01*
G03X566510Y247323I-749J3421D01*
G03X565840Y249382I-3503J-1D01*
G02Y249618I162J118D01*
G03X566510Y251677I-2833J2060D01*
G03X563757Y255098I-3502J0D01*
G01X563688Y255113D01*
X563600Y255223D01*
Y262819D01*
G02X563800Y263019I200J0D01*
G01X574023D01*
G02X574155Y262969I0J-200D01*
G03X576467Y262098I2311J2631D01*
G03X578779Y262969I1J3502D01*
G02X578911Y263019I132J-150D01*
G37*
G36*
G01X719159Y199605D02*
X720515Y200961D01*
G02X720657Y201020I142J-141D01*
G01X759056D01*
G02X759198Y200961I0J-200D01*
G01X760053Y200106D01*
G02X760112Y199964I-141J-142D01*
G01Y184590D01*
G02X760053Y184448I-200J0D01*
G01X746664Y171059D01*
G02X746522Y171000I-142J141D01*
G01X732511D01*
G02X732369Y171059I0J200D01*
G01X719159Y184269D01*
G02X719100Y184411I141J142D01*
G01Y199463D01*
G02X719159Y199605I200J0D01*
G37*
G36*
G01X1190270Y263135D02*
X1197800D01*
G02X1198000Y262935I0J-200D01*
G01Y255072D01*
G02X1197880Y254889I-200J0D01*
G03X1195774Y251677I1396J-3212D01*
G03X1196444Y249618I3503J1D01*
G02Y249382I-162J-118D01*
G03X1195774Y247323I2833J-2060D01*
G03X1197880Y244111I3502J0D01*
G02X1198000Y243928I-80J-183D01*
G01Y165611D01*
G02X1197941Y165469I-200J0D01*
G01X1195917Y163445D01*
X1195887Y163430D01*
G03X1194279Y161822I1538J-3146D01*
G02X1194241Y161769I-179J89D01*
G01X1194031Y161559D01*
G02X1193889Y161500I-142J141D01*
G01X1183800D01*
G03X1182386Y160914I0J-1999D01*
G01X1176414Y154942D01*
G03X1175828Y153528I1413J-1414D01*
G01Y132192D01*
G03X1176414Y130778I1999J0D01*
G01X1176795Y130397D01*
G03X1178209Y129811I1414J1413D01*
G01X1185265D01*
G02X1185396Y129762I0J-200D01*
G03X1187700Y128898I2303J2638D01*
G03X1190004Y129762I1J3502D01*
G02X1190135Y129811I131J-151D01*
G01X1196878D01*
G02X1197020Y129752I0J-200D01*
G01X1197941Y128831D01*
G02X1198000Y128689I-141J-142D01*
G01Y121872D01*
G02X1197880Y121689I-200J0D01*
G03X1195774Y118477I1396J-3212D01*
G03X1196444Y116418I3503J1D01*
G02Y116182I-162J-118D01*
G03X1195774Y114123I2833J-2060D01*
G03X1197880Y110911I3502J0D01*
G02X1198000Y110728I-80J-183D01*
G01Y52911D01*
G02X1197941Y52769I-200J0D01*
G01X1196231Y51059D01*
G02X1196089Y51000I-142J141D01*
G01X1116478D01*
G02X1116336Y51059I0J200D01*
G01X1103059Y64336D01*
G02X1103000Y64478I141J142D01*
G01Y107017D01*
G03X1102414Y108431I-1999J0D01*
G01X1097431Y113414D01*
G03X1096017Y114000I-1414J-1413D01*
G01X910911D01*
G02X910769Y114059I0J200D01*
G01X905059Y119769D01*
G02X905000Y119911I141J142D01*
G01Y184089D01*
G02X905059Y184231I200J0D01*
G01X907269Y186441D01*
G02X907411Y186500I142J-141D01*
G01X955640D01*
G02X955782Y186441I0J-200D01*
G01X978875Y163348D01*
G03X980289Y162762I1414J1413D01*
G01X1007462D01*
G03X1008876Y163348I0J1999D01*
G01X1018569Y173041D01*
G02X1018711Y173100I142J-141D01*
G01X1055000D01*
G03X1056414Y173686I0J1999D01*
G01X1112169Y229441D01*
G02X1112311Y229500I142J-141D01*
G01X1155100D01*
G03X1156514Y230086I0J1999D01*
G01X1168914Y242486D01*
G03X1169500Y243900I-1413J1414D01*
G01Y257089D01*
G02X1169559Y257231I200J0D01*
G01X1175404Y263076D01*
G02X1175546Y263135I142J-141D01*
G01X1185130D01*
G02X1185269Y263079I0J-200D01*
G03X1190131I2431J2522D01*
G02X1190270Y263135I139J-144D01*
G37*
G36*
G01X973547Y200106D02*
X974402Y200961D01*
G02X974544Y201020I142J-141D01*
G01X1012943D01*
G02X1013085Y200961I0J-200D01*
G01X1014441Y199605D01*
G02X1014500Y199463I-141J-142D01*
G01Y184411D01*
G02X1014441Y184269I-200J0D01*
G01X1001231Y171059D01*
G02X1001089Y171000I-142J141D01*
G01X987078D01*
G02X986936Y171059I0J200D01*
G01X973547Y184448D01*
G02X973488Y184590I141J142D01*
G01Y199964D01*
G02X973547Y200106I200J0D01*
G37*
G36*
G01X1426030Y660444D02*
G03Y653178I3105J-3633D01*
G02X1426100Y653026I-130J-152D01*
G01Y652722D01*
G02X1426030Y652570I-200J0D01*
G03X1424356Y648937I3105J-3633D01*
G03X1429134Y644158I4779J0D01*
G03X1432767Y645833I-1J4779D01*
G02X1432919Y645903I152J-130D01*
G01X1433223D01*
G02X1433375Y645833I0J-200D01*
G03X1437008Y644158I3634J3104D01*
G03X1441786Y648935I0J4778D01*
G01Y648937D01*
G03X1440112Y652570I-4779J0D01*
G02X1440042Y652722I130J152D01*
G01Y653026D01*
G02X1440112Y653178I200J0D01*
G03X1441324Y654759I-3103J3634D01*
G02X1441447Y654865I181J-86D01*
G01X1441729Y654950D01*
G02X1441889Y654931I58J-191D01*
G03X1447875I2993J5030D01*
G02X1448035Y654950I102J-172D01*
G01X1448317Y654865D01*
G02X1448440Y654759I-58J-192D01*
G03X1449652Y653178I4315J2053D01*
G02X1449722Y653026I-130J-152D01*
G01Y652722D01*
G02X1449652Y652570I-200J0D01*
G03X1447978Y648937I3105J-3633D01*
G03X1452756Y644158I4779J0D01*
G03X1456389Y645833I-1J4779D01*
G02X1456541Y645903I152J-130D01*
G01X1456845D01*
G02X1456997Y645833I0J-200D01*
G03X1460630Y644158I3634J3104D01*
G03X1465408Y648935I0J4778D01*
G01Y648937D01*
G03X1463734Y652570I-4779J0D01*
G02X1463664Y652722I130J152D01*
G01Y653026D01*
G02X1463734Y653178I200J0D01*
G03Y660444I-3105J3633D01*
G02X1463664Y660596I130J152D01*
G01Y660900D01*
G02X1463734Y661052I200J0D01*
G03X1465408Y664685I-3105J3633D01*
G03X1460630Y669464I-4779J0D01*
G03X1456997Y667789I1J-4779D01*
G02X1456845Y667719I-152J130D01*
G01X1456541D01*
G02X1456389Y667789I0J200D01*
G03X1452756Y669464I-3634J-3104D01*
G03X1448047Y665498I0J-4779D01*
G02X1447941Y665353I-197J33D01*
G01X1447613Y665186D01*
X1447519D01*
X1447476Y665207D01*
G03X1442288I-2594J-5246D01*
G01X1442245Y665186D01*
X1442151D01*
X1441823Y665353D01*
G02X1441717Y665498I91J178D01*
G03X1437008Y669464I-4709J-813D01*
G03X1433375Y667789I1J-4779D01*
G02X1433223Y667719I-152J130D01*
G01X1432919D01*
G02X1432767Y667789I0J200D01*
G03X1431880Y668595I-3632J-3105D01*
G02X1431820Y668856I115J164D01*
G03X1432256Y670547I-3065J1692D01*
G03X1432240Y670879I-3502J-2D01*
G02X1432380Y671089I199J19D01*
G02X1437006Y671787I4627J-14987D01*
G01X1442324D01*
G02X1442513Y671651I0J-200D01*
G03X1449145I3316J1127D01*
G02X1449334Y671787I189J-64D01*
G01X1462324D01*
G02X1462513Y671651I0J-200D01*
G03X1469145I3316J1127D01*
G02X1469334Y671787I189J-64D01*
G01X1482324D01*
G02X1482513Y671651I0J-200D01*
G03X1483586Y670089I3315J1128D01*
G01X1483587Y670088D01*
G02X1483652Y669884I-129J-153D01*
G01X1483559Y669533D01*
G02X1483402Y669387I-193J51D01*
G01X1483401D01*
G03X1480619Y667789I851J-4702D01*
G02X1480467Y667719I-152J130D01*
G01X1480163D01*
G02X1480011Y667789I0J200D01*
G03X1476378Y669464I-3634J-3104D01*
G03X1471600Y664687I0J-4778D01*
G01Y664685D01*
G03X1473274Y661052I4779J0D01*
G02X1473344Y660900I-130J-152D01*
G01Y660596D01*
G02X1473274Y660444I-200J0D01*
G03Y653178I3105J-3633D01*
G02X1473344Y653026I-130J-152D01*
G01Y652722D01*
G02X1473274Y652570I-200J0D01*
G03X1471600Y648937I3105J-3633D01*
G03X1476378Y644158I4779J0D01*
G03X1480011Y645833I-1J4779D01*
G02X1480163Y645903I152J-130D01*
G01X1480467D01*
G02X1480619Y645833I0J-200D01*
G03X1484252Y644158I3634J3104D01*
G03X1489030Y648935I0J4778D01*
G01Y648937D01*
G03X1487356Y652570I-4779J0D01*
G02X1487286Y652722I130J152D01*
G01Y653026D01*
G02X1487356Y653178I200J0D01*
G03Y660444I-3105J3633D01*
G02X1487286Y660596I130J152D01*
G01Y660900D01*
G02X1487356Y661052I200J0D01*
G03X1489030Y664685I-3105J3633D01*
G01Y664686D01*
G03X1486806Y668724I-4778J0D01*
G02X1486714Y668919I106J169D01*
G01X1486760Y669278D01*
X1486897Y669443D01*
G03X1489145Y671651I-1068J3335D01*
G02X1489334Y671787I189J-64D01*
G01X1502324D01*
G02X1502513Y671651I0J-200D01*
G03X1505647Y669281I3316J1127D01*
G01X1505648D01*
G02X1505829Y669138I-11J-200D01*
G01X1505936Y668776D01*
G02X1505861Y668557I-192J-57D01*
G03X1503882Y664685I2800J-3873D01*
G03X1505557Y661052I4779J1D01*
G02X1505627Y660900I-130J-152D01*
G01Y660596D01*
G02X1505557Y660444I-200J0D01*
G03X1503882Y656811I3104J-3634D01*
G03X1505557Y653178I4779J1D01*
G02X1505627Y653026I-130J-152D01*
G01Y652722D01*
G02X1505557Y652570I-200J0D01*
G03X1503882Y648937I3104J-3634D01*
G03X1508661Y644158I4779J0D01*
G03X1512294Y645833I-1J4779D01*
G02X1512446Y645903I152J-130D01*
G01X1512750D01*
G02X1512902Y645833I0J-200D01*
G03X1516535Y644158I3634J3104D01*
G03X1521314Y648937I0J4779D01*
G03X1519639Y652570I-4779J-1D01*
G02X1519569Y652722I130J152D01*
G01Y653026D01*
G02X1519639Y653178I200J0D01*
G03X1521314Y656811I-3104J3634D01*
G03X1519639Y660444I-4779J-1D01*
G02X1519569Y660596I130J152D01*
G01Y660900D01*
G02X1519639Y661052I200J0D01*
G03X1521314Y664685I-3104J3634D01*
G03X1516535Y669464I-4779J0D01*
G03X1512902Y667789I1J-4779D01*
G02X1512750Y667719I-152J130D01*
G01X1512446D01*
G02X1512294Y667789I0J200D01*
G03X1508661Y669464I-3634J-3104D01*
G03X1508437Y669458I16J-4779D01*
G01X1508435D01*
G02X1508241Y669583I-9J200D01*
G01X1508099Y669932D01*
G02X1508152Y670157I185J75D01*
G03X1509145Y671651I-2323J2621D01*
G02X1509334Y671787I189J-64D01*
G01X1522324D01*
G02X1522513Y671651I0J-200D01*
G03X1529145I3316J1127D01*
G02X1529334Y671787I189J-64D01*
G01X1542324D01*
G02X1542513Y671651I0J-200D01*
G03X1549145I3316J1127D01*
G02X1549334Y671787I189J-64D01*
G01X1562324D01*
G02X1562513Y671651I0J-200D01*
G03X1569145I3316J1127D01*
G02X1569334Y671787I189J-64D01*
G01X1582324D01*
G02X1582513Y671651I0J-200D01*
G03X1584589Y669503I3316J1127D01*
G01X1584590D01*
G02X1584718Y669333I-71J-187D01*
G01X1584750Y668975D01*
G02X1584654Y668786I-199J-18D01*
G01X1584653Y668785D01*
G03X1582328Y664685I2454J-4101D01*
G03X1584003Y661052I4779J1D01*
G02X1584073Y660900I-130J-152D01*
G01Y660596D01*
G02X1584003Y660444I-200J0D01*
G03X1582328Y656811I3104J-3634D01*
G03X1584003Y653178I4779J1D01*
G02X1584073Y653026I-130J-152D01*
G01Y652722D01*
G02X1584003Y652570I-200J0D01*
G03X1582328Y648937I3104J-3634D01*
G03X1584003Y645304I4779J1D01*
G02X1584073Y645152I-130J-152D01*
G01Y644848D01*
G02X1584003Y644696I-200J0D01*
G03X1582328Y641063I3104J-3634D01*
G03X1584003Y637430I4779J1D01*
G02X1584073Y637278I-130J-152D01*
G01Y636974D01*
G02X1584003Y636822I-200J0D01*
G03X1582328Y633189I3104J-3634D01*
G03X1584003Y629556I4779J1D01*
G02X1584073Y629404I-130J-152D01*
G01Y629100D01*
G02X1584003Y628948I-200J0D01*
G03X1582328Y625315I3104J-3634D01*
G03X1584003Y621682I4779J1D01*
G02X1584073Y621530I-130J-152D01*
G01Y621226D01*
G02X1584003Y621074I-200J0D01*
G03X1582328Y617441I3104J-3634D01*
G03X1584003Y613808I4779J1D01*
G02X1584073Y613656I-130J-152D01*
G01Y613352D01*
G02X1584003Y613200I-200J0D01*
G03X1582328Y609567I3104J-3634D01*
G03X1584003Y605934I4779J1D01*
G02X1584073Y605782I-130J-152D01*
G01Y605478D01*
G02X1584003Y605326I-200J0D01*
G03X1582328Y601693I3104J-3634D01*
G03X1587107Y596914I4779J0D01*
G03X1590740Y598589I-1J4779D01*
G02X1590892Y598659I152J-130D01*
G01X1591196D01*
G02X1591348Y598589I0J-200D01*
G03X1594981Y596914I3634J3104D01*
G03X1599760Y601693I0J4779D01*
G03X1598085Y605326I-4779J-1D01*
G02X1598015Y605478I130J152D01*
G01Y605782D01*
G02X1598085Y605934I200J0D01*
G03X1599760Y609567I-3104J3634D01*
G03X1598085Y613200I-4779J-1D01*
G02X1598015Y613352I130J152D01*
G01Y613656D01*
G02X1598085Y613808I200J0D01*
G03X1599760Y617441I-3104J3634D01*
G03X1598085Y621074I-4779J-1D01*
G02X1598015Y621226I130J152D01*
G01Y621530D01*
G02X1598085Y621682I200J0D01*
G03X1599760Y625315I-3104J3634D01*
G03X1598085Y628948I-4779J-1D01*
G02X1598015Y629100I130J152D01*
G01Y629404D01*
G02X1598085Y629556I200J0D01*
G03X1599760Y633189I-3104J3634D01*
G03X1598085Y636822I-4779J-1D01*
G02X1598015Y636974I130J152D01*
G01Y637278D01*
G02X1598085Y637430I200J0D01*
G03X1599760Y641063I-3104J3634D01*
G03X1598085Y644696I-4779J-1D01*
G02X1598015Y644848I130J152D01*
G01Y645152D01*
G02X1598085Y645304I200J0D01*
G03X1599760Y648937I-3104J3634D01*
G03X1598085Y652570I-4779J-1D01*
G02X1598015Y652722I130J152D01*
G01Y653026D01*
G02X1598085Y653178I200J0D01*
G03X1599760Y656811I-3104J3634D01*
G03X1598085Y660444I-4779J-1D01*
G02X1598015Y660596I130J152D01*
G01Y660900D01*
G02X1598085Y661052I200J0D01*
G03X1599759Y664591I-3104J3634D01*
G01Y664592D01*
G02X1599875Y664768I200J-5D01*
G01X1600196Y664918D01*
G02X1600406Y664892I84J-182D01*
G03X1602598Y664122I2192J2736D01*
G01X1602599D01*
G03X1603733Y664311I-2J3506D01*
G01X1603798Y664322D01*
G02X1603969Y664225I0J-200D01*
G02X1606236Y656104I-13418J-8123D01*
G01Y653953D01*
G02X1606100Y653764I-200J0D01*
G03Y647132I1126J-3316D01*
G02X1606236Y646943I-64J-189D01*
G01Y642912D01*
G03X1610546Y629289I23685J0D01*
G01X1610582Y629174D01*
X1610552Y629068D01*
G03X1610025Y627220I2977J-1848D01*
G03X1613527Y623718I3502J0D01*
G03X1615243Y624168I-1J3501D01*
G02X1615464Y624152I98J-174D01*
G03X1615890Y623831I14466J18754D01*
G03X1625069Y619730I14031J19082D01*
G01X1625224Y619574D01*
G03X1628658Y616759I3434J687D01*
G03X1631960Y619095I0J3502D01*
G02X1632148Y619228I188J-67D01*
G01X1643098D01*
G02X1643240Y619169I0J-200D01*
G01X1645945Y616464D01*
G02X1646004Y616322I-141J-142D01*
G01Y310215D01*
G02X1645945Y310073I-200J0D01*
G01X1643431Y307559D01*
G02X1643289Y307500I-142J141D01*
G01X1597100D01*
G03X1595686Y306914I0J-1999D01*
G01X1581686Y292914D01*
G03X1581100Y291500I1413J-1414D01*
G01Y176309D01*
G02X1581041Y176167I-200J0D01*
G01X1532933Y128059D01*
G02X1532791Y128000I-142J141D01*
G01X1457900D01*
G03X1456486Y127414I0J-1999D01*
G01X1392531Y63459D01*
G02X1392389Y63400I-142J141D01*
G01X1299614D01*
G03X1298200Y62814I0J-1999D01*
G01X1280341Y44955D01*
G02X1280124Y44912I-141J142D01*
G01X1280067Y44935D01*
X1280000Y45036D01*
Y314500D01*
G03X1279414Y315914I-1999J0D01*
G01X1276914Y318414D01*
G03X1275500Y319000I-1414J-1413D01*
G01X1225966D01*
G03X1224552Y318414I0J-1999D01*
G01X1221901Y315763D01*
G03X1221315Y314349I1413J-1414D01*
G01Y304866D01*
G02X1221165Y304673I-200J1D01*
G01X1220790Y304576D01*
G02X1220565Y304671I-51J193D01*
G01Y304673D01*
G03X1212478Y309432I-8087J-4492D01*
G03X1203227Y300181I0J-9251D01*
G03X1203875Y296780I9252J0D01*
G01X1203899Y296720D01*
X1203868Y296596D01*
X1203530Y296308D01*
G02X1203298Y296289I-129J153D01*
G03X1201500Y296786I-1798J-3004D01*
G01X1201499D01*
G03X1199190Y295917I0J-3503D01*
G02X1199058Y295867I-132J150D01*
G01X1198942D01*
G02X1198810Y295917I0J200D01*
G03X1196501Y296786I-2309J-2634D01*
G01X1196500D01*
G03X1193061Y293946I0J-3502D01*
G01X1193047Y293875D01*
X1192937Y293784D01*
X1159970D01*
G02X1159787Y293903I0J200D01*
G03X1159767Y293948I-3210J-1400D01*
G01X1159749Y294031D01*
X1159763Y294105D01*
G03X1160009Y295395I-3254J1289D01*
G01Y295396D01*
G03X1153009I-3500J0D01*
G01Y295394D01*
G03X1153182Y294308I3501J1D01*
G01X1153192Y294245D01*
G02X1153154Y294128I-200J0D01*
G01X1152964Y293866D01*
G02X1152803Y293784I-162J118D01*
G01X1124554D01*
G02X1124383Y293881I0J200D01*
G01X1124206Y294174D01*
G02X1124200Y294369I171J103D01*
G01Y294370D01*
G03X1124602Y295999I-3100J1629D01*
G01Y296000D01*
G03X1123881Y298128I-3502J0D01*
G02Y298372I159J122D01*
G03X1124602Y300499I-2781J2128D01*
G01Y300500D01*
G03X1117598I-3502J0D01*
G01Y300499D01*
G03X1118319Y298372I3502J1D01*
G02Y298128I-159J-122D01*
G03X1117598Y296000I2781J-2128D01*
G01Y295999D01*
G03X1118000Y294370I3502J0D01*
G01Y294369D01*
G02X1117994Y294174I-177J-92D01*
G01X1117817Y293881D01*
G02X1117646Y293784I-171J103D01*
G01X1115454D01*
G02X1115283Y293881I0J200D01*
G01X1115106Y294174D01*
G02X1115100Y294369I171J103D01*
G01Y294370D01*
G03X1115502Y295999I-3100J1629D01*
G01Y296001D01*
G03X1114270Y298668I-3502J0D01*
G01X1114199Y298821D01*
X1114221Y298911D01*
G03X1114602Y300498I-3121J1589D01*
G01Y300500D01*
G03X1107598I-3502J0D01*
G01Y300499D01*
G03X1108830Y297832I3502J0D01*
G01X1108901Y297679D01*
X1108879Y297589D01*
G03X1108498Y296001I3121J-1589D01*
G01Y295999D01*
G03X1108879Y294411I3502J1D01*
G01X1108901Y294321D01*
X1108830Y294168D01*
G03X1108503Y293850I2273J-2665D01*
G01X1108355Y293784D01*
X1106054D01*
G02X1105883Y293881I0J200D01*
G01X1105706Y294174D01*
G02X1105700Y294369I171J103D01*
G01Y294370D01*
G03X1106102Y295998I-3100J1629D01*
G01Y296000D01*
G03X1099098I-3502J0D01*
G01Y295998D01*
G03X1099500Y294370I3502J1D01*
G01Y294369D01*
G02X1099494Y294174I-177J-92D01*
G01X1099317Y293881D01*
G02X1099146Y293784I-171J103D01*
G01X1084302D01*
G02X1084102Y293984I0J200D01*
G01Y294000D01*
G03X1077098I-3502J0D01*
G01Y293984D01*
G02X1076898Y293784I-200J0D01*
G01X1076604D01*
X1076428Y293890D01*
G03X1073339Y295741I-3089J-1652D01*
G03X1070665Y294500I0J-3501D01*
G01X1070512Y294429D01*
X1070490D01*
G03X1068515Y293819I0J-3502D01*
G01X1068402Y293784D01*
X1065320D01*
G03X1063906Y293198I0J-1999D01*
G01X1056979Y286271D01*
G03X1056393Y284857I1413J-1414D01*
G01Y283482D01*
G02X1056327Y283334I-200J1D01*
G01X1056075Y283107D01*
X1055995Y283081D01*
X1055953Y283085D01*
G03X1055600Y283102I-345J-3485D01*
G03Y276098I0J-3502D01*
G03X1055953Y276115I8J3502D01*
G01X1055995Y276119D01*
X1056075Y276093D01*
X1056327Y275866D01*
G02X1056393Y275718I-134J-149D01*
G01Y272382D01*
G02X1056327Y272234I-200J1D01*
G01X1056075Y272007D01*
X1055995Y271981D01*
X1055953Y271985D01*
G03X1055600Y272002I-345J-3485D01*
G03Y264998I0J-3502D01*
G01X1055601D01*
G03X1056134Y265039I-1J3502D01*
G01X1056136D01*
G02X1056276Y265008I30J-198D01*
G01X1056407Y264921D01*
X1056449Y264861D01*
X1056458Y264826D01*
G03X1056979Y263920I1934J509D01*
G01X1074407Y246492D01*
G02X1074466Y246350I-141J-142D01*
G01Y228083D01*
G02X1074407Y227941I-200J0D01*
G01X1073115Y226649D01*
G02X1072973Y226590I-142J141D01*
G01X1031531D01*
G02X1031389Y226649I0J200D01*
G01X1027704Y230334D01*
G02X1027645Y230476I141J142D01*
G01Y300379D01*
G02X1027760Y300560I200J0D01*
G03Y306898I-1490J3169D01*
G02X1027645Y307079I85J181D01*
G01Y335678D01*
G02X1027704Y335820I200J0D01*
G01X1038814Y346930D01*
G02X1038956Y346989I142J-141D01*
G01X1134867D01*
G02X1135063Y346828I0J-200D01*
G01Y346827D01*
G03X1138500Y343998I3437J673D01*
G03X1139919Y344299I-1J3502D01*
G02X1140081I81J-183D01*
G03X1141500Y343998I1420J3201D01*
G03X1144937Y346827I0J3502D01*
G01Y346828D01*
G02X1145133Y346989I196J-39D01*
G01X1165913D01*
X1166036Y346946D01*
G03X1168199Y346198I2163J2755D01*
G01X1168200D01*
G03X1170031Y346715I-1J3503D01*
G02X1170221Y346726I105J-170D01*
G03X1171700Y346398I1480J3175D01*
G03X1173598Y346957I0J3502D01*
G01X1173599D01*
G02X1173707Y346989I108J-168D01*
G01X1174174D01*
X1174224Y346975D01*
X1174247Y346962D01*
G03X1175990Y346498I1743J3040D01*
G01X1176000D01*
G03X1177655Y346914I0J3502D01*
G01X1177750Y346938D01*
X1177845Y346914D01*
G03X1179500Y346498I1655J3086D01*
G01X1179502D01*
G03X1181243Y346962I-1J3501D01*
G01X1181342Y346989D01*
X1295200D01*
G03X1297200Y348989I0J2000D01*
G01Y399209D01*
G02X1297303Y399384I200J0D01*
G01X1297610Y399553D01*
G02X1297706Y399578I97J-175D01*
G01X1297813Y399547D01*
G03X1299680Y399008I1867J2964D01*
G03X1302994Y401377I0J3502D01*
G01X1303015Y401438D01*
X1303118Y401512D01*
X1316242D01*
X1316345Y401438D01*
X1316366Y401377D01*
G03X1322994I3314J1133D01*
G01X1323015Y401438D01*
X1323118Y401512D01*
X1336242D01*
X1336345Y401438D01*
X1336366Y401377D01*
G03X1342994I3314J1133D01*
G01X1343015Y401438D01*
X1343118Y401512D01*
X1354331D01*
G03X1356257Y401568I-11J33527D01*
G02X1356450Y401453I12J-200D01*
G03X1359620Y399438I3170J1486D01*
G03X1363100Y402548I0J3502D01*
G02X1363246Y402718I199J-23D01*
G03X1387611Y430979I-8916J32320D01*
G01X1387760Y431148D01*
G03X1390384Y434539I-879J3391D01*
G03X1387994Y437860I-3502J0D01*
G01X1387933Y437881D01*
X1387858Y437985D01*
Y451029D01*
G02X1387994Y451218I200J0D01*
G03Y457860I-1112J3321D01*
G01X1387933Y457881D01*
X1387858Y457985D01*
Y471029D01*
G02X1387994Y471218I200J0D01*
G03Y477860I-1112J3321D01*
G01X1387933Y477881D01*
X1387858Y477985D01*
Y491029D01*
G02X1387994Y491218I200J0D01*
G03Y497860I-1112J3321D01*
G01X1387933Y497881D01*
X1387858Y497985D01*
Y511029D01*
G02X1387994Y511218I200J0D01*
G03Y517860I-1112J3321D01*
G01X1387933Y517881D01*
X1387858Y517985D01*
Y531029D01*
G02X1387994Y531218I200J0D01*
G03Y537860I-1112J3321D01*
G01X1387933Y537881D01*
X1387858Y537985D01*
Y551029D01*
G02X1387994Y551218I200J0D01*
G03Y557860I-1112J3321D01*
G01X1387933Y557881D01*
X1387858Y557985D01*
Y571029D01*
G02X1387994Y571218I200J0D01*
G03Y577860I-1112J3321D01*
G01X1387933Y577881D01*
X1387858Y577985D01*
Y591029D01*
G02X1387994Y591218I200J0D01*
G03Y597860I-1112J3321D01*
G01X1387933Y597881D01*
X1387858Y597985D01*
Y603543D01*
G02X1388889Y609136I15685J0D01*
G02X1389107Y609262I187J-72D01*
G03X1389639Y609221I534J3461D01*
G01X1389643D01*
G03X1393145Y612723I0J3502D01*
G03X1392615Y614575I-3502J0D01*
G01X1392585Y614681D01*
G02X1392646Y614825I200J0D01*
G02X1399664Y618741I10897J-11282D01*
G02X1399893Y618635I49J-194D01*
G03X1403035Y616679I3142J1546D01*
G03X1406373Y619123I0J3502D01*
G02X1406551Y619263I191J-60D01*
G03X1414255Y621865I-1037J15777D01*
G03X1416285Y623466I-8743J13174D01*
G03X1419408Y627496I-10773J11573D01*
G03X1419766Y628197I-13898J7539D01*
G03X1419776Y628218I-14270J6808D01*
G03X1420993Y631826I-14264J6821D01*
G02X1421143Y631980I196J-41D01*
G03X1423837Y635388I-809J3408D01*
G03X1421459Y638705I-3502J0D01*
G02X1421323Y638894I64J189D01*
G01Y651882D01*
G02X1421459Y652071I200J0D01*
G03X1423837Y655388I-1124J3317D01*
G03X1421684Y658620I-3502J0D01*
G01X1421561Y658805D01*
G02X1421564Y658840I200J0D01*
G02X1421625Y659168I15450J-2704D01*
G02X1423647Y664318I15382J-3067D01*
G02X1423861Y664408I170J-105D01*
G01X1424230Y664325D01*
X1424385Y664152D01*
G03X1426030Y661052I4749J533D01*
G02X1426100Y660900I-130J-152D01*
G01Y660596D01*
G02X1426030Y660444I-200J0D01*
G37*
G36*
G01X1204711Y180500D02*
X1275089D01*
G02X1275231Y180441I0J-200D01*
G01X1275941Y179731D01*
G02X1276000Y179589I-141J-142D01*
G01Y52411D01*
G02X1275941Y52269I-200J0D01*
G01X1274731Y51059D01*
G02X1274589Y51000I-142J141D01*
G01X1203911D01*
G02X1203769Y51059I0J200D01*
G01X1202059Y52769D01*
G02X1202000Y52911I141J142D01*
G01Y111850D01*
G02X1202042Y111973I200J0D01*
G03X1202780Y114123I-2765J2151D01*
G03X1202110Y116182I-3503J-1D01*
G02Y116418I162J118D01*
G03X1202780Y118477I-2833J2060D01*
G03X1202042Y120627I-3503J-1D01*
G02X1202000Y120750I158J123D01*
G01Y128789D01*
G02X1202059Y128931I200J0D01*
G01X1202880Y129752D01*
G02X1203022Y129811I142J-141D01*
G01X1208065D01*
G02X1208196Y129762I0J-200D01*
G03X1210500Y128898I2303J2638D01*
G03X1212804Y129762I1J3502D01*
G02X1212935Y129811I131J-151D01*
G01X1219382D01*
G03X1220796Y130397I0J1999D01*
G01X1224817Y134418D01*
G03X1225403Y135832I-1413J1414D01*
G01Y153697D01*
G03X1224817Y155111I-1999J0D01*
G01X1219014Y160914D01*
G03X1217600Y161500I-1414J-1413D01*
G01X1204111D01*
G02X1203969Y161559I0J200D01*
G01X1203736Y161792D01*
X1203721Y161822D01*
G03X1202113Y163430I-3146J-1538D01*
G01X1202083Y163445D01*
X1202059Y163469D01*
G02X1202000Y163611I141J142D01*
G01Y177789D01*
G02X1202059Y177931I200J0D01*
G01X1204569Y180441D01*
G02X1204711Y180500I142J-141D01*
G37*
G36*
G01X1226877Y315000D02*
X1274589D01*
G02X1274731Y314941I0J-200D01*
G01X1275941Y313731D01*
G02X1276000Y313589I-141J-142D01*
G01Y185411D01*
G02X1275941Y185269I-200J0D01*
G01X1275231Y184559D01*
G02X1275089Y184500I-142J141D01*
G01X1202200D01*
G02X1202000Y184700I0J200D01*
G01Y245050D01*
G02X1202042Y245173I200J0D01*
G03X1202780Y247323I-2765J2151D01*
G03X1202110Y249382I-3503J-1D01*
G02Y249618I162J118D01*
G03X1202780Y251677I-2833J2060D01*
G03X1202042Y253827I-3503J-1D01*
G02X1202000Y253950I158J123D01*
G01Y262935D01*
G02X1202200Y263135I200J0D01*
G01X1207930D01*
G02X1208069Y263079I0J-200D01*
G03X1212931I2431J2522D01*
G02X1213070Y263135I139J-144D01*
G01X1219718D01*
G03X1221132Y263721I0J1999D01*
G01X1224729Y267318D01*
G03X1225315Y268732I-1413J1414D01*
G01Y313438D01*
G02X1225374Y313580I200J0D01*
G01X1226735Y314941D01*
G02X1226877Y315000I142J-141D01*
G37*
G36*
G01X1856652Y514607D02*
G02X1870016Y499095I-2321J-15513D01*
G01Y498327D01*
G02X1869956Y498184I-200J0D01*
G03Y496040I1052J-1072D01*
G02X1870016Y495897I-140J-143D01*
G01Y478327D01*
G02X1869956Y478184I-200J0D01*
G03Y476040I1052J-1072D01*
G02X1870016Y475897I-140J-143D01*
G01Y458327D01*
G02X1869956Y458184I-200J0D01*
G03Y456040I1052J-1072D01*
G02X1870016Y455897I-140J-143D01*
G01Y438327D01*
G02X1869956Y438184I-200J0D01*
G03Y436040I1052J-1072D01*
G02X1870016Y435897I-140J-143D01*
G01Y418327D01*
G02X1869956Y418184I-200J0D01*
G03Y416040I1052J-1072D01*
G02X1870016Y415897I-140J-143D01*
G01Y398327D01*
G02X1869956Y398184I-200J0D01*
G03Y396040I1052J-1072D01*
G02X1870016Y395897I-140J-143D01*
G01Y378327D01*
G02X1869956Y378184I-200J0D01*
G03Y376040I1052J-1072D01*
G02X1870016Y375897I-140J-143D01*
G01Y358327D01*
G02X1869956Y358184I-200J0D01*
G03Y356040I1052J-1072D01*
G02X1870016Y355897I-140J-143D01*
G01Y338327D01*
G02X1869956Y338184I-200J0D01*
G03Y336040I1052J-1072D01*
G02X1870016Y335897I-140J-143D01*
G01Y318327D01*
G02X1869956Y318184I-200J0D01*
G03Y316040I1052J-1072D01*
G02X1870016Y315897I-140J-143D01*
G01Y298327D01*
G02X1869956Y298184I-200J0D01*
G03Y296040I1052J-1072D01*
G02X1870016Y295897I-140J-143D01*
G01Y278327D01*
G02X1869956Y278184I-200J0D01*
G03Y276040I1052J-1072D01*
G02X1870016Y275897I-140J-143D01*
G01Y258327D01*
G02X1869956Y258184I-200J0D01*
G03Y256040I1052J-1072D01*
G02X1870016Y255897I-140J-143D01*
G01Y238327D01*
G02X1869956Y238184I-200J0D01*
G03Y236040I1052J-1072D01*
G02X1870016Y235897I-140J-143D01*
G01Y218327D01*
G02X1869956Y218184I-200J0D01*
G03Y216040I1052J-1072D01*
G02X1870016Y215897I-140J-143D01*
G01Y198327D01*
G02X1869956Y198184I-200J0D01*
G03Y196040I1052J-1072D01*
G02X1870016Y195897I-140J-143D01*
G01Y178327D01*
G02X1869956Y178184I-200J0D01*
G03Y176040I1052J-1072D01*
G02X1870016Y175897I-140J-143D01*
G01Y158327D01*
G02X1869956Y158184I-200J0D01*
G03Y156040I1052J-1072D01*
G02X1870016Y155897I-140J-143D01*
G01Y138327D01*
G02X1869956Y138184I-200J0D01*
G03Y136040I1052J-1072D01*
G02X1870016Y135897I-140J-143D01*
G01Y118327D01*
G02X1869956Y118184I-200J0D01*
G03Y116040I1052J-1072D01*
G02X1870016Y115897I-140J-143D01*
G01Y95127D01*
G02X1869956Y94984I-200J0D01*
G03Y92842I1053J-1071D01*
G02X1870016Y92699I-140J-143D01*
G01Y85709D01*
G02X1854853Y70033I-15685J0D01*
G02X1854704Y70092I-7J200D01*
G03X1853635Y70539I-1069J-1055D01*
G03X1852559Y70085I0J-1502D01*
G02X1852415Y70024I-144J139D01*
G01X1834855D01*
G02X1834711Y70085I0J200D01*
G03X1832559I-1076J-1048D01*
G02X1832415Y70024I-144J139D01*
G01X1814855D01*
G02X1814711Y70085I0J200D01*
G03X1812559I-1076J-1048D01*
G02X1812415Y70024I-144J139D01*
G01X1794855D01*
G02X1794711Y70085I0J200D01*
G03X1792559I-1076J-1048D01*
G02X1792415Y70024I-144J139D01*
G01X1774855D01*
G02X1774711Y70085I0J200D01*
G03X1772559I-1076J-1048D01*
G02X1772415Y70024I-144J139D01*
G01X1754855D01*
G02X1754711Y70085I0J200D01*
G03X1752559I-1076J-1048D01*
G02X1752415Y70024I-144J139D01*
G01X1751968D01*
G03X1732632Y60018I0J-23686D01*
G02X1732506Y59937I-163J115D01*
G03X1731284Y58461I280J-1476D01*
G03X1731333Y58080I1502J0D01*
G02X1731314Y57931I-193J-51D01*
G03X1728284Y46580I20654J-11593D01*
G02X1728222Y46437I-200J2D01*
G03X1727753Y45347I1032J-1090D01*
G03X1728221Y44258I1501J0D01*
G02X1728283Y44113I-138J-145D01*
G01Y26581D01*
G02X1728221Y26436I-200J0D01*
G03Y24258I1033J-1089D01*
G02X1728283Y24113I-138J-145D01*
G01Y19685D01*
G02X1712598Y4000I-15685J0D01*
G01X1709670D01*
G02X1709528Y4059I0J200D01*
G03X1707392I-1068J-1056D01*
G02X1707250Y4000I-142J141D01*
G01X1670271D01*
G02X1670129Y4059I0J200D01*
G01X1666194Y7993D01*
G03X1666135Y8051I-2132J-2110D01*
G02X1666073Y8195I138J145D01*
G01Y44962D01*
G02X1666132Y45104I200J0D01*
G01X1686899Y65871D01*
G02X1687041Y65930I142J-141D01*
G01X1713492D01*
G03X1714906Y66516I0J1999D01*
G01X1759361Y110971D01*
X1759438Y111001D01*
X1759479Y111000D01*
G03X1759600Y110998I118J3500D01*
G03X1763102Y114500I0J3502D01*
G03X1763100Y114621I-3502J3D01*
G01X1763099Y114662D01*
X1763129Y114739D01*
X1764375Y115984D01*
X1764437Y116014D01*
X1764471Y116017D01*
G03X1767583Y119129I-371J3483D01*
G01X1767586Y119163D01*
X1767616Y119225D01*
X1774530Y126140D01*
X1774570Y126165D01*
X1774593Y126172D01*
G03X1776828Y128407I-1093J3328D01*
G01X1776835Y128430D01*
X1776860Y128470D01*
X1783931Y135541D01*
G02X1784073Y135600I142J-141D01*
G01X1813000D01*
G03X1814414Y136186I0J1999D01*
G01X1839914Y161686D01*
G03X1840500Y163100I-1413J1414D01*
G01Y260389D01*
G02X1840559Y260531I200J0D01*
G01X1843469Y263441D01*
G02X1843611Y263500I142J-141D01*
G01X1860900D01*
G03X1862314Y264086I0J1999D01*
G01X1864814Y266586D01*
G03X1865400Y268000I-1413J1414D01*
G01Y303000D01*
G03X1864814Y304414I-1999J0D01*
G01X1862314Y306914D01*
G03X1860900Y307500I-1414J-1413D01*
G01X1652957D01*
G02X1652815Y307559I0J200D01*
G01X1650063Y310311D01*
G02X1650004Y310453I141J142D01*
G01Y616322D01*
G02X1650063Y616464I200J0D01*
G01X1652768Y619169D01*
G02X1652910Y619228I142J-141D01*
G01X1667466D01*
G02X1667608Y619169I0J-200D01*
G03X1669742I1067J1057D01*
G02X1669884Y619228I142J-141D01*
G01X1687449D01*
G02X1687595Y619165I0J-200D01*
G03X1689789I1097J1026D01*
G02X1689935Y619228I146J-137D01*
G01X1707449D01*
G02X1707595Y619165I0J-200D01*
G03X1709789I1097J1026D01*
G02X1709935Y619228I146J-137D01*
G01X1712598D01*
G02X1728277Y603966I0J-15685D01*
G02X1728218Y603818I-200J-6D01*
G03X1727773Y602751I1057J-1067D01*
G03X1728223Y601679I1502J0D01*
G02X1728283Y601536I-140J-143D01*
G01Y583966D01*
G02X1728223Y583823I-200J0D01*
G03Y581679I1052J-1072D01*
G02X1728283Y581536I-140J-143D01*
G01Y563966D01*
G02X1728223Y563823I-200J0D01*
G03Y561679I1052J-1072D01*
G02X1728283Y561536I-140J-143D01*
G01Y543966D01*
G02X1728223Y543823I-200J0D01*
G03Y541679I1052J-1072D01*
G02X1728283Y541536I-140J-143D01*
G01Y538465D01*
G03X1751968Y514780I23686J0D01*
G01X1754214D01*
G02X1754360Y514717I0J-200D01*
G03X1756548I1094J1029D01*
G02X1756694Y514780I146J-137D01*
G01X1774214D01*
G02X1774360Y514717I0J-200D01*
G03X1776548I1094J1029D01*
G02X1776694Y514780I146J-137D01*
G01X1814214D01*
G02X1814360Y514717I0J-200D01*
G03X1816548I1094J1029D01*
G02X1816694Y514780I146J-137D01*
G01X1834214D01*
G02X1834360Y514717I0J-200D01*
G03X1836548I1094J1029D01*
G02X1836694Y514780I146J-137D01*
G01X1854225D01*
G02X1854376Y514711I0J-200D01*
G03X1855509Y514195I1133J986D01*
G03X1856491Y514561I-1J1502D01*
G02X1856652Y514607I130J-152D01*
G37*
%LPD*%
G75*
G36*
G01X586796Y282890D02*
G02X593800I3502J0D01*
G02X592588Y280240I-3503J0D01*
G03X592519Y280089I131J-151D01*
G01Y279785D01*
G03X592588Y279634I200J0D01*
G02X593800Y276984I-2291J-2650D01*
G02X586796I-3502J0D01*
G02X588008Y279634I3503J0D01*
G03X588077Y279785I-131J151D01*
G01Y280089D01*
G03X588008Y280240I-200J0D01*
G02X586796Y282890I2291J2650D01*
G37*
G36*
G01X568040Y289065D02*
Y289066D01*
G02X568410Y290633I3502J0D01*
G03X568398Y290832I-179J89D01*
G02X567822Y292757I2926J1924D01*
G02X574828I3503J0D01*
G02X574457Y291189I-3503J1D01*
G03X574469Y290990I179J-89D01*
G02X575044Y289068I-2928J-1923D01*
G01Y289065D01*
G02X568040I-3502J0D01*
G37*
G36*
G01X565091Y299090D02*
G02Y306094I0J3502D01*
G01X565092D01*
G02X567440Y305190I0J-3502D01*
G01X567469Y305164D01*
X567540Y305137D01*
X567853Y305143D01*
G03X567989Y305201I-5J200D01*
G02X570442Y306204I2453J-2499D01*
G01X570443D01*
G02Y299200I0J-3502D01*
G01X570442D01*
G02X568094Y300104I0J3502D01*
G01X568065Y300130D01*
X567994Y300157D01*
X567681Y300151D01*
G03X567545Y300093I5J-200D01*
G02X565092Y299090I-2453J2499D01*
G01X565091D01*
G37*
G36*
G01X616684Y304472D02*
G02Y311478I0J3503D01*
G02X619141Y310471I-1J-3503D01*
G03X619282Y310413I141J142D01*
G01X619564Y310415D01*
G03X619704Y310473I-1J200D01*
G01X619705Y310474D01*
G02X622184Y311502I2479J-2475D01*
G02Y304498I0J-3502D01*
G01X622183D01*
G02X619727Y305504I1J3502D01*
G03X619586Y305562I-141J-142D01*
G01X619304Y305560D01*
G03X619164Y305502I1J-200D01*
G01X619163Y305501D01*
G02X616684Y304472I-2480J2474D01*
G37*
G36*
G01X587182Y310800D02*
Y310802D01*
G02X587482Y312219I3502J-1D01*
G03Y312381I-183J81D01*
G02X587182Y313798I3202J1418D01*
G01Y313800D01*
G02X594186I3502J0D01*
G01Y313798D01*
G02X593886Y312381I-3502J1D01*
G03Y312219I183J-81D01*
G02X594186Y310802I-3202J-1418D01*
G01Y310800D01*
G02X587182I-3502J0D01*
G37*
G36*
G01X713600Y320666D02*
G02X712406Y320876I0J3499D01*
G03X712260Y320873I-69J-188D01*
G02X710901Y320598I-1360J3227D01*
G01X710900D01*
G02X707398Y324100I0J3502D01*
G02X709996Y327484I3503J0D01*
G03X710142Y327646I-52J193D01*
G02X713600Y330600I3458J-547D01*
G02X717100Y327100I0J-3500D01*
G01Y327099D01*
G02X716813Y325712I-3500J1D01*
G03Y325554I184J-79D01*
G02X717100Y324167I-3213J-1388D01*
G01Y324166D01*
G02X713600Y320666I-3500J0D01*
G37*
G36*
G01X1744422Y204000D02*
G02X1747925Y207502I3503J-1D01*
G02X1751276Y205019I0J-3503D01*
G03X1751439Y204879I191J58D01*
G01X1751856Y204820D01*
X1751961Y204868D01*
X1751993Y204917D01*
G02X1754923Y206502I2931J-1918D01*
G01X1754925D01*
G02Y199498I0J-3502D01*
G01X1754921D01*
G02X1754357Y199544I2J3502D01*
G03X1754174Y199478I-32J-197D01*
G01X1753950Y199222D01*
G03X1753910Y199032I151J-131D01*
G01Y199031D01*
G02X1754066Y198000I-3347J-1034D01*
G02X1747060I-3503J0D01*
G02X1747638Y199927I3503J0D01*
G03X1747654Y200118I-167J110D01*
G01X1747498Y200472D01*
X1747418Y200534D01*
X1747368Y200542D01*
G02X1744422Y204000I556J3458D01*
G37*
G36*
G01X1741952Y190104D02*
G02X1738740Y187998I-3212J1396D01*
G02Y195002I0J3502D01*
G02X1742044Y192663I0J-3503D01*
G03X1742788Y192636I377J133D01*
G02X1746000Y194742I3212J-1396D01*
G02Y187738I0J-3502D01*
G02X1742696Y190077I0J3503D01*
G03X1741952Y190104I-377J-133D01*
G37*
G36*
G01X1619241Y157954D02*
G02X1622100Y159434I2859J-2021D01*
G02X1624344Y158620I-1J-3503D01*
G03X1624605Y158624I128J153D01*
G02X1626924Y159502I2319J-2624D01*
G01X1626925D01*
G02Y152498I0J-3502D01*
G02X1624681Y153311I0J3503D01*
G03X1624420Y153307I-128J-153D01*
G02X1622100Y152428I-2321J2624D01*
G02X1621172Y152553I-1J3503D01*
G03X1620956Y152476I-53J-193D01*
G02X1620550Y152000I-2856J2025D01*
G01X1620521Y151972D01*
X1620489Y151897D01*
X1620490Y151571D01*
G03X1620550Y151428I200J0D01*
G02X1621602Y148991I-2450J-2503D01*
G01X1621603Y148933D01*
X1621666Y148837D01*
X1622046Y148662D01*
G03X1622258Y148691I83J182D01*
G02X1624498Y149502I2241J-2691D01*
G01X1624500D01*
G02X1628002Y146000I0J-3502D01*
G01Y145998D01*
G02X1627587Y144344I-3502J0D01*
G03Y144156I176J-94D01*
G02X1628002Y142502I-3087J-1654D01*
G01Y142500D01*
G02X1620998I-3502J0D01*
G01Y142502D01*
G02X1621413Y144155I3502J-1D01*
G03Y144345I-176J95D01*
G02X1620998Y145934I3087J1655D01*
G01X1620997Y145992D01*
X1620934Y146088D01*
X1620554Y146263D01*
G03X1620342Y146234I-83J-182D01*
G02X1618100Y145422I-2243J2691D01*
G02X1614598Y148925I1J3503D01*
G01Y148926D01*
G02X1615650Y151428I3502J0D01*
G03X1615710Y151571I-140J143D01*
G01X1615711Y151857D01*
G03X1615651Y152000I-200J0D01*
G02X1614600Y154500I2448J2500D01*
G02X1618100Y158000I3500J0D01*
G01X1618102D01*
G02X1619025Y157876I0J-3500D01*
G03X1619241Y157954I52J193D01*
G37*
G36*
G01X1716791Y142684D02*
G02X1714100Y141422I-2692J2240D01*
G02Y148428I0J3503D01*
G02X1717601Y145012I0J-3502D01*
G03X1718309Y144766I400J10D01*
G02X1721000Y146028I2692J-2240D01*
G02Y139022I0J-3503D01*
G02X1717499Y142438I0J3502D01*
G03X1716791Y142684I-400J-10D01*
G37*
G36*
G01X1653828Y115388D02*
G02X1653548Y116759I3222J1372D01*
G01Y116760D01*
G02X1657050Y120262I3502J0D01*
G01X1657053D01*
G02X1658564Y119919I-1J-3502D01*
G03X1658736I86J180D01*
G02X1660247Y120262I1512J-3159D01*
G01X1660250D01*
G02X1663752Y116760I0J-3502D01*
G01Y116759D01*
G02X1663472Y115388I-3502J1D01*
G03Y115232I184J-78D01*
G02X1663752Y113861I-3222J-1372D01*
G01Y113860D01*
G02X1660250Y110358I-3502J0D01*
G01X1660247D01*
G02X1658736Y110701I1J3502D01*
G03X1658564I-86J-180D01*
G02X1657053Y110358I-1512J3159D01*
G01X1657050D01*
G02X1654130Y111926I0J3503D01*
G01X1654094Y111980D01*
X1653975Y112026D01*
X1653545Y111911D01*
G03X1653397Y111732I52J-193D01*
G01Y111731D01*
G02X1650002Y108548I-3395J219D01*
G01X1649999D01*
G02X1648328Y108987I1J3403D01*
G03X1648132I-98J-174D01*
G02X1646458Y108548I-1672J2964D01*
G02X1644784Y108987I-2J3403D01*
G03X1644588I-98J-174D01*
G02X1642915Y108548I-1672J2963D01*
G02X1641242Y108987I-1J3402D01*
G03X1641046I-98J-174D01*
G02X1639375Y108548I-1672J2964D01*
G01X1639372D01*
G02X1635970Y111950I0J3402D01*
G01Y111955D01*
G02X1636181Y113131I3402J-4D01*
G03Y113269I-188J69D01*
G02X1635970Y114445I3191J1180D01*
G01Y114450D01*
G02X1639372Y117852I3402J0D01*
G01X1639375D01*
G02X1641046Y117413I-1J-3403D01*
G03X1641242I98J174D01*
G02X1642915Y117852I1672J-2963D01*
G02X1644588Y117413I1J-3402D01*
G03X1644784I98J174D01*
G02X1646458Y117852I1672J-2964D01*
G02X1648132Y117413I2J-3403D01*
G03X1648328I98J174D01*
G02X1649999Y117852I1672J-2964D01*
G01X1650002D01*
G02X1653354Y115035I0J-3403D01*
G03X1653357Y115022I196J38D01*
G03X1653731Y114982I194J48D01*
G03X1653740Y115004I-180J87D01*
G02X1653828Y115232I3309J-1146D01*
G03Y115388I-184J78D01*
G37*
G36*
G01X1748098Y255500D02*
G02X1748303Y256683I3502J2D01*
G03Y256817I-188J67D01*
G02X1748098Y257997I3297J1181D01*
G01Y258000D01*
G02X1755102I3502J0D01*
G01Y257997D01*
G02X1754897Y256817I-3502J1D01*
G03Y256683I188J-67D01*
G02X1755102Y255500I-3297J-1181D01*
G02X1754897Y254317I-3502J-2D01*
G03Y254183I188J-67D01*
G02X1755102Y253000I-3297J-1181D01*
G02X1754897Y251817I-3502J-2D01*
G03Y251683I188J-67D01*
G02X1755102Y250500I-3297J-1181D01*
G02X1754897Y249317I-3502J-2D01*
G03Y249183I188J-67D01*
G02X1755102Y248003I-3297J-1181D01*
G01Y248000D01*
G02X1748098I-3502J0D01*
G01Y248003D01*
G02X1748303Y249183I3502J-1D01*
G03Y249317I-188J67D01*
G02X1748098Y250500I3297J1181D01*
G02X1748303Y251683I3502J2D01*
G03Y251817I-188J67D01*
G02X1748098Y253000I3297J1181D01*
G02X1748303Y254183I3502J2D01*
G03Y254317I-188J67D01*
G02X1748098Y255500I3297J1181D01*
G37*
G36*
G01X1737098D02*
G02X1737303Y256683I3502J2D01*
G03Y256817I-188J67D01*
G02X1737098Y257997I3297J1181D01*
G01Y258000D01*
G02X1744102I3502J0D01*
G01Y257997D01*
G02X1743897Y256817I-3502J1D01*
G03Y256683I188J-67D01*
G02X1744102Y255500I-3297J-1181D01*
G02X1743897Y254317I-3502J-2D01*
G03Y254183I188J-67D01*
G02X1744102Y253000I-3297J-1181D01*
G02X1743897Y251817I-3502J-2D01*
G03Y251683I188J-67D01*
G02X1744102Y250500I-3297J-1181D01*
G02X1743897Y249317I-3502J-2D01*
G03Y249183I188J-67D01*
G02X1744102Y248003I-3297J-1181D01*
G01Y248000D01*
G02X1737098I-3502J0D01*
G01Y248003D01*
G02X1737303Y249183I3502J-1D01*
G03Y249317I-188J67D01*
G02X1737098Y250500I3297J1181D01*
G02X1737303Y251683I3502J2D01*
G03Y251817I-188J67D01*
G02X1737098Y253000I3297J1181D01*
G02X1737303Y254183I3502J2D01*
G03Y254317I-188J67D01*
G02X1737098Y255500I3297J1181D01*
G37*
G36*
G01X1780430Y247357D02*
G02X1780730Y248776I3502J1D01*
G03Y248938I-183J81D01*
G02X1780430Y250357I3202J1418D01*
G02X1783932Y253860I3502J1D01*
G02X1787433Y250467I0J-3503D01*
G01X1787434Y250415D01*
X1787486Y250327D01*
X1787866Y250103D01*
X1787968Y250099D01*
X1788014Y250123D01*
G02X1789597Y250502I1585J-3123D01*
G01X1789600D01*
G02X1793102Y247000I0J-3502D01*
G01Y246998D01*
G02X1792687Y245344I-3502J0D01*
G03Y245156I176J-94D01*
G02X1793102Y243502I-3087J-1654D01*
G01Y243500D01*
G02X1789600Y239998I-3502J0D01*
G01X1789596D01*
G02X1788023Y240372I2J3503D01*
G01X1787974Y240397D01*
X1787869Y240391D01*
X1787534Y240171D01*
G03X1787444Y239993I110J-167D01*
G02X1787450Y239798I-3497J-205D01*
G02X1780444I-3503J0D01*
G02X1780745Y241217I3503J-2D01*
G03Y241379I-183J81D01*
G02X1780444Y242798I3202J1421D01*
G02X1781180Y244946I3502J0D01*
G03X1781179Y245192I-158J122D01*
G02X1780430Y247357I2753J2165D01*
G37*
G36*
G01X1771930D02*
G02X1772230Y248776I3502J1D01*
G03Y248938I-183J81D01*
G02X1771930Y250355I3202J1418D01*
G01Y250357D01*
G02X1778934I3502J0D01*
G01Y250355D01*
G02X1778634Y248938I-3502J1D01*
G03Y248776I183J-81D01*
G02X1778934Y247357I-3202J-1418D01*
G02X1778199Y245209I-3502J-1D01*
G03X1778200Y244963I158J-122D01*
G02X1778950Y242798I-2753J-2166D01*
G02X1778649Y241379I-3503J2D01*
G03Y241217I183J-81D01*
G02X1778950Y239798I-3202J-1421D01*
G02X1771944I-3503J0D01*
G02X1772245Y241217I3503J-2D01*
G03Y241379I-183J81D01*
G02X1771944Y242798I3202J1421D01*
G02X1772680Y244946I3502J0D01*
G03X1772679Y245192I-158J122D01*
G02X1771930Y247357I2753J2165D01*
G37*
G36*
G01X1762930Y247301D02*
Y247303D01*
G02X1763230Y248720I3502J-1D01*
G03Y248882I-183J81D01*
G02X1762930Y250299I3202J1418D01*
G01Y250301D01*
G02X1769934I3502J0D01*
G01Y250299D01*
G02X1769634Y248882I-3502J1D01*
G03Y248720I183J-81D01*
G02X1769934Y247301I-3202J-1418D01*
G02X1769219Y245180I-3502J0D01*
G03X1769220Y244937I159J-121D01*
G02X1769950Y242798I-2772J-2140D01*
G02X1769649Y241379I-3503J2D01*
G03Y241217I183J-81D01*
G02X1769950Y239798I-3202J-1421D01*
G02X1762944I-3503J0D01*
G02X1763245Y241217I3503J-2D01*
G03Y241379I-183J81D01*
G02X1762944Y242798I3202J1421D01*
G02X1763660Y244919I3503J-1D01*
G03X1763659Y245162I-159J121D01*
G02X1762930Y247301I2774J2139D01*
G37*
G36*
G01X1748098Y238000D02*
G02X1748303Y239183I3502J2D01*
G03Y239317I-188J67D01*
G02X1748098Y240497I3297J1181D01*
G01Y240500D01*
G02X1755102I3502J0D01*
G01Y240497D01*
G02X1754897Y239317I-3502J1D01*
G03Y239183I188J-67D01*
G02X1755102Y238000I-3297J-1181D01*
G02X1754897Y236817I-3502J-2D01*
G03Y236683I188J-67D01*
G02X1755102Y235500I-3297J-1181D01*
G02X1754897Y234317I-3502J-2D01*
G03Y234183I188J-67D01*
G02X1755102Y233003I-3297J-1181D01*
G01Y233000D01*
G02X1748098I-3502J0D01*
G01Y233003D01*
G02X1748303Y234183I3502J-1D01*
G03Y234317I-188J67D01*
G02X1748098Y235500I3297J1181D01*
G02X1748303Y236683I3502J2D01*
G03Y236817I-188J67D01*
G02X1748098Y238000I3297J1181D01*
G37*
G36*
G01X1737098D02*
G02X1737303Y239183I3502J2D01*
G03Y239317I-188J67D01*
G02X1737098Y240497I3297J1181D01*
G01Y240500D01*
G02X1744102I3502J0D01*
G01Y240497D01*
G02X1743897Y239317I-3502J1D01*
G03Y239183I188J-67D01*
G02X1744102Y238000I-3297J-1181D01*
G02X1743897Y236817I-3502J-2D01*
G03Y236683I188J-67D01*
G02X1744102Y235500I-3297J-1181D01*
G02X1743897Y234317I-3502J-2D01*
G03Y234183I188J-67D01*
G02X1744102Y233003I-3297J-1181D01*
G01Y233000D01*
G02X1737098I-3502J0D01*
G01Y233003D01*
G02X1737303Y234183I3502J-1D01*
G03Y234317I-188J67D01*
G02X1737098Y235500I3297J1181D01*
G02X1737303Y236683I3502J2D01*
G03Y236817I-188J67D01*
G02X1737098Y238000I3297J1181D01*
G37*
G36*
G01X1657998Y199000D02*
G02X1660500Y202357I3503J0D01*
G02X1660498Y202499I3500J120D01*
G01Y202501D01*
G02X1664000Y206002I3502J-1D01*
G02X1667502Y202500I0J-3502D01*
G02X1667501Y202402I-3502J-13D01*
G01Y202401D01*
G03X1667552Y202263I200J-5D01*
G01X1667763Y202029D01*
X1667831Y201995D01*
X1667870Y201992D01*
G02X1671102Y198500I-270J-3492D01*
G02X1667600Y194998I-3502J0D01*
G01X1667599D01*
G02X1664685Y196558I0J3502D01*
G03X1664534Y196647I-167J-110D01*
G01X1664177Y196676D01*
X1664091Y196643D01*
X1664060Y196609D01*
G02X1663135Y195902I-2560J2391D01*
G01X1663098Y195883D01*
X1663046Y195819D01*
X1662947Y195456D01*
X1662959Y195375D01*
X1662981Y195339D01*
G02X1663502Y193502I-2981J-1838D01*
G01Y193500D01*
G02X1660790Y190087I-3504J0D01*
G03X1660655Y189980I45J-195D01*
G02X1657500Y187998I-3155J1520D01*
G02X1655007Y189041I1J3502D01*
G03X1654818Y189095I-142J-141D01*
G02X1654001Y188998I-819J3405D01*
G01X1654000D01*
G02Y196002I0J3502D01*
G02X1656493Y194960I0J-3503D01*
G03X1656683Y194906I143J140D01*
G02X1656710Y194912I773J-3416D01*
G03X1656845Y195020I-45J195D01*
G02X1658365Y196598I3156J-1519D01*
G01X1658402Y196617D01*
X1658454Y196681D01*
X1658553Y197044D01*
X1658541Y197125D01*
X1658519Y197161D01*
G02X1657998Y198998I2981J1838D01*
G01Y199000D01*
G37*
G36*
G01X1811500Y182498D02*
G02Y189502I0J3502D01*
G01X1811504D01*
G02X1813544Y188845I-2J-3503D01*
G01X1813582Y188817D01*
X1813677Y188802D01*
X1814077Y188935D01*
X1814144Y189004D01*
X1814158Y189050D01*
G02X1817499Y191502I3341J-1051D01*
G01X1817500D01*
G02Y184498I0J-3502D01*
G01X1817496D01*
G02X1815456Y185155I2J3503D01*
G01X1815418Y185183D01*
X1815323Y185198D01*
X1814923Y185065D01*
X1814856Y184996D01*
X1814842Y184950D01*
G02X1811501Y182498I-3341J1051D01*
G01X1811500D01*
G37*
G36*
G01X1764498Y187260D02*
G02X1771502I3502J0D01*
G01Y187257D01*
G02X1770975Y185411I-3502J2D01*
G01X1770951Y185372D01*
X1770941Y185281D01*
X1771063Y184943D01*
G03X1771188Y184821I188J68D01*
G02X1773578Y181500I-1112J-3321D01*
G02X1773520Y180867I-3503J2D01*
G03X1773656Y180640I196J-37D01*
G02X1776102Y177300I-1057J-3340D01*
G01Y177296D01*
G02X1775687Y175644I-3503J2D01*
G03X1775681Y175466I176J-95D01*
G02X1776002Y174003I-3181J-1465D01*
G01Y174000D01*
G02X1772968Y170529I-3502J0D01*
G01X1772966D01*
G03X1772819Y170427I28J-198D01*
G01X1772663Y170145D01*
G03X1772657Y169966I176J-95D01*
G01Y169965D01*
G02X1772978Y168501I-3181J-1465D01*
G01Y168500D01*
G02X1769476Y164998I-3502J0D01*
G02X1766088Y167611I0J3503D01*
G01X1766077Y167655D01*
X1766018Y167723D01*
X1765693Y167870D01*
G03X1765520Y167865I-81J-183D01*
G01X1765519D01*
G02X1763928Y167482I-1593J3119D01*
G01X1763925D01*
G02Y174486I0J3502D01*
G02X1767313Y171873I0J-3503D01*
G01X1767324Y171829D01*
X1767383Y171761D01*
X1767708Y171614D01*
G03X1767881Y171619I81J183D01*
G01X1767882D01*
G02X1769008Y171971I1593J-3119D01*
G01X1769010D01*
G03X1769157Y172073I-28J198D01*
G01X1769313Y172355D01*
G03X1769319Y172534I-176J95D01*
G01Y172535D01*
G02X1768998Y174000I3181J1465D01*
G02X1769413Y175656I3503J2D01*
G03X1769419Y175834I-176J95D01*
G02X1769098Y177297I3181J1465D01*
G01Y177300D01*
G02X1769156Y177933I3501J-2D01*
G03X1769020Y178160I-197J36D01*
G02X1768585Y178330I1055J3340D01*
G03X1768415Y178331I-86J-180D01*
G02X1766925Y177998I-1491J3170D01*
G01X1766924D01*
G02X1766630Y178010I-4J3502D01*
G03X1766422Y177870I-17J-199D01*
G02X1763075Y175398I-3347J1030D01*
G02X1761585Y175731I1J3503D01*
G03X1761415I-85J-181D01*
G02X1759925Y175398I-1491J3170D01*
G02Y182402I0J3502D01*
G02X1761415Y182069I-1J-3503D01*
G03X1761585I85J181D01*
G02X1763075Y182402I1491J-3170D01*
G01X1763076D01*
G02X1763370Y182390I4J-3502D01*
G03X1763578Y182530I17J199D01*
G02X1765133Y184509I3347J-1030D01*
G01X1765134Y184510D01*
G03X1765227Y184644I-103J171D01*
G01X1765290Y184983D01*
X1765270Y185066D01*
X1765243Y185100D01*
G02X1764498Y187259I2757J2159D01*
G01Y187260D01*
G37*
G36*
G01X1645000Y180998D02*
G02X1643581Y181298I-1J3502D01*
G03X1643419I-81J-183D01*
G02X1642002Y180998I-1418J3202D01*
G01X1642000D01*
G02Y188002I0J3502D01*
G01X1642002D01*
G02X1643419Y187702I-1J-3502D01*
G03X1643581I81J183D01*
G02X1644998Y188002I1418J-3202D01*
G01X1645000D01*
G02X1648502Y184500I0J-3502D01*
G01Y184496D01*
G02X1648424Y183763I-3502J2D01*
G01X1648412Y183710D01*
X1648446Y183606D01*
X1648750Y183340D01*
G03X1648948Y183302I132J151D01*
G01X1648949D01*
G02X1650117Y183502I1167J-3302D01*
G02X1653620Y180000I1J-3502D01*
G02X1651680Y176865I-3503J0D01*
G01X1651633Y176842D01*
X1651575Y176757D01*
X1651533Y176315D01*
X1651575Y176220D01*
X1651616Y176189D01*
G02X1653002Y173398I-2117J-2791D01*
G02X1645998I-3502J0D01*
G01Y173400D01*
G02X1647937Y176533I3503J-1D01*
G01X1647984Y176556D01*
X1648042Y176641D01*
X1648084Y177083D01*
X1648042Y177178D01*
X1648001Y177209D01*
G02X1646614Y180000I2115J2791D01*
G02X1646693Y180737I3503J-3D01*
G01X1646705Y180790D01*
X1646671Y180894D01*
X1646367Y181160D01*
G03X1646169Y181198I-132J-151D01*
G01X1646168D01*
G02X1645000Y180998I-1167J3302D01*
G37*
G36*
G01X1619598Y178000D02*
G02X1623100Y181502I3502J0D01*
G02X1626589Y178308I0J-3503D01*
G01X1626594Y178256D01*
X1626651Y178172D01*
X1627000Y177994D01*
G03X1627194Y178001I91J178D01*
G02X1628998Y178502I1805J-3001D01*
G01X1629000D01*
G02Y171498I0J-3502D01*
G02X1627133Y172037I0J3503D01*
G01X1627132D01*
G03X1626948Y172052I-106J-169D01*
G01X1626600Y171904D01*
X1626538Y171829D01*
X1626528Y171781D01*
G02X1626437Y171437I-3427J723D01*
G01X1626424Y171397D01*
X1626433Y171313D01*
X1626625Y170983D01*
X1626693Y170934D01*
X1626735Y170925D01*
G02X1629502Y167500I-736J-3425D01*
G02X1628947Y165608I-3502J0D01*
G03Y165392I168J-108D01*
G02X1629502Y163500I-2947J-1892D01*
G02X1622498I-3502J0D01*
G02X1623053Y165392I3502J0D01*
G03Y165608I-168J108D01*
G02X1622498Y167500I2947J1892D01*
G01Y167501D01*
G02X1622663Y168563I3502J0D01*
G01X1622676Y168603D01*
X1622667Y168687D01*
X1622475Y169017D01*
X1622407Y169066D01*
X1622365Y169075D01*
G02X1619598Y172500I736J3425D01*
G02X1620615Y174968I3503J0D01*
G01X1620616Y174969D01*
G03X1620673Y175109I-143J140D01*
G01Y175391D01*
G03X1620616Y175531I-200J0D01*
G01X1620615Y175532D01*
G02X1619598Y178000I2486J2468D01*
G37*
G36*
G01X1760422Y155484D02*
G02X1760672Y156783I3503J-1D01*
G03X1760676Y156920I-186J74D01*
G02X1760498Y158025I3324J1102D01*
G02X1764000Y161528I3502J1D01*
G02X1766128Y160806I-2J-3502D01*
G03X1766372I122J159D01*
G02X1768500Y161528I2130J-2780D01*
G02X1770644Y160795I0J-3502D01*
G03X1770887Y160794I122J158D01*
G02X1772998Y161502I2111J-2794D01*
G01X1773000D01*
G02Y154498I0J-3502D01*
G01X1772998D01*
G02X1771115Y155048I1J3502D01*
G01X1771074Y155075D01*
X1770975Y155083D01*
X1770626Y154934D01*
G03X1770508Y154790I78J-184D01*
G02X1767075Y151982I-3433J695D01*
G02X1765585Y152315I1J3503D01*
G03X1765415I-85J-181D01*
G02X1763925Y151982I-1491J3170D01*
G01X1763923D01*
G02X1760422Y155484I1J3502D01*
G37*
G36*
G01X1764000Y146028D02*
G02X1766128Y145306I-2J-3502D01*
G03X1766372I122J159D01*
G02X1768500Y146028I2130J-2780D01*
G02X1770628Y145306I-2J-3502D01*
G03X1770872I122J159D01*
G02X1773000Y146028I2130J-2780D01*
G02X1776502Y142525I-1J-3503D01*
G02X1773946Y139153I-3502J0D01*
G01X1773945D01*
G03X1773817Y139041I55J-192D01*
G01X1773693Y138757D01*
G03X1773698Y138587I183J-80D01*
G01Y138586D01*
G02X1774078Y137000I-3123J-1587D01*
G02X1770575Y133498I-3503J1D01*
G02X1769085Y133831I1J3503D01*
G03X1768915I-85J-181D01*
G02X1767425Y133498I-1491J3170D01*
G01X1767423D01*
G02X1763922Y137000I1J3502D01*
G02X1764240Y138458I3503J0D01*
G01X1764261Y138503D01*
X1764255Y138603D01*
X1764054Y138929D01*
G03X1763889Y139024I-170J-105D01*
G02X1760498Y142525I112J3501D01*
G01Y142527D01*
G02X1764000Y146028I3502J-1D01*
G37*
G36*
G01X1710602Y142500D02*
G02X1708443Y139265I-3503J0D01*
G03X1708335Y139157I77J-185D01*
G02X1705100Y136998I-3235J1344D01*
G02X1701598Y140500I0J3502D01*
G02X1703757Y143735I3503J0D01*
G03X1703865Y143843I-77J185D01*
G02X1707100Y146002I3235J-1344D01*
G02X1710602Y142500I0J-3502D01*
G37*
G36*
G01X1710942Y131942D02*
Y132058D01*
G03X1710892Y132190I-200J0D01*
G02X1710022Y134500I2633J2310D01*
G02X1717028I3503J0D01*
G02X1716158Y132190I-3503J0D01*
G03X1716108Y132058I150J-132D01*
G01Y131942D01*
G03X1716158Y131810I200J0D01*
G02X1717028Y129500I-2633J-2310D01*
G02X1710022I-3503J0D01*
G02X1710892Y131810I3503J0D01*
G03X1710942Y131942I-150J132D01*
G37*
G36*
G01X1681498Y133000D02*
G02X1688502I3502J0D01*
G01Y132998D01*
G02X1687453Y130500I-3502J1D01*
G03X1687393Y130354I140J-143D01*
G01X1687396Y130232D01*
G03X1687461Y130087I200J3D01*
G02X1687476Y130074I-2286J-2653D01*
G03X1687606Y130021I136J147D01*
G01X1687723Y130018D01*
G03X1687857Y130064I6J200D01*
G02X1690100Y130878I2245J-2688D01*
G02Y123872I0J-3503D01*
G02X1687724Y124801I0J3503D01*
G03X1687594Y124854I-136J-147D01*
G01X1687477Y124857D01*
G03X1687343Y124811I-6J-200D01*
G02X1685846Y124078I-2244J2689D01*
G01X1685844D01*
G03X1685706Y123966I44J-195D01*
G01X1685572Y123674D01*
G03X1685578Y123497I182J-82D01*
G01Y123496D01*
G02X1686002Y121825I-3078J-1670D01*
G02X1682500Y118322I-3502J-1D01*
G02X1679843Y119543I1J3503D01*
G01X1679842Y119544D01*
G03X1679650Y119609I-151J-131D01*
G01X1679306Y119536D01*
G03X1679156Y119397I42J-196D01*
G02X1675800Y116898I-3356J1004D01*
G01X1675798D01*
G02X1674381Y117198I1J3502D01*
G03X1674219I-81J-183D01*
G02X1672800Y116898I-1418J3202D01*
G02X1671381Y117198I-1J3502D01*
G03X1671219I-81J-183D01*
G02X1669802Y116898I-1418J3202D01*
G01X1669800D01*
G02Y123902I0J3502D01*
G01X1669802D01*
G02X1671219Y123602I-1J-3502D01*
G03X1671381I81J183D01*
G02X1672800Y123902I1418J-3202D01*
G02X1674219Y123602I1J-3502D01*
G03X1674381I81J183D01*
G02X1675798Y123902I1418J-3202D01*
G01X1675800D01*
G02X1678457Y122682I0J-3503D01*
G01X1678458Y122681D01*
G03X1678650Y122616I151J131D01*
G01X1678994Y122689D01*
G03X1679144Y122828I-42J196D01*
G02X1681754Y125247I3356J-1003D01*
G01X1681756D01*
G03X1681894Y125359I-44J195D01*
G01X1682028Y125651D01*
G03X1682022Y125828I-182J82D01*
G01Y125829D01*
G02X1681598Y127500I3078J1670D01*
G02X1682571Y129923I3502J0D01*
G01X1682572Y129924D01*
G03X1682627Y130065I-145J138D01*
G01X1682621Y130347D01*
G03X1682562Y130486I-200J-3D01*
G01X1682561Y130487D01*
G02X1681498Y133000I2439J2513D01*
G37*
G36*
G01X1611517Y127441D02*
Y127559D01*
G03X1611467Y127690I-200J-1D01*
G02X1610598Y130000I2634J2309D01*
G02X1617602I3502J0D01*
G02X1616733Y127690I-3503J-1D01*
G03X1616683Y127559I150J-132D01*
G01Y127441D01*
G03X1616733Y127310I200J1D01*
G02Y122690I-2634J-2310D01*
G03X1616683Y122559I150J-132D01*
G01Y122441D01*
G03X1616733Y122310I200J1D01*
G02Y117690I-2634J-2310D01*
G03X1616683Y117559I150J-132D01*
G01Y117441D01*
G03X1616733Y117310I200J1D01*
G02Y112690I-2634J-2310D01*
G03X1616683Y112559I150J-132D01*
G01Y112441D01*
G03X1616733Y112310I200J1D01*
G02X1617602Y110000I-2634J-2309D01*
G02X1610598I-3502J0D01*
G02X1611467Y112310I3503J1D01*
G03X1611517Y112441I-150J132D01*
G01Y112559D01*
G03X1611467Y112690I-200J-1D01*
G02Y117310I2634J2310D01*
G03X1611517Y117441I-150J132D01*
G01Y117559D01*
G03X1611467Y117690I-200J-1D01*
G02Y122310I2634J2310D01*
G03X1611517Y122441I-150J132D01*
G01Y122559D01*
G03X1611467Y122690I-200J-1D01*
G02Y127310I2634J2310D01*
G03X1611517Y127441I-150J132D01*
G37*
G36*
G01X1651325Y128578D02*
X1651329D01*
G02X1652794Y128256I-2J-3502D01*
G01X1652832Y128238D01*
X1652918Y128237D01*
X1653270Y128388D01*
X1653327Y128450D01*
X1653340Y128490D01*
G02X1656657Y130868I3317J-1124D01*
G02Y123862I0J-3503D01*
G02X1655188Y124185I0J3502D01*
G01X1655150Y124203D01*
X1655064Y124204D01*
X1654712Y124053D01*
X1654655Y123991D01*
X1654642Y123951D01*
G02X1654337Y123288I-3317J1124D01*
G03X1654319Y123124I172J-102D01*
G02X1654492Y122036I-3329J-1087D01*
G01Y122034D01*
G02X1650990Y118532I-3502J0D01*
G01X1650987D01*
G02X1649721Y118769I0J3502D01*
G03X1649551Y118757I-72J-186D01*
G02X1647839Y118310I-1712J3055D01*
G01X1647837D01*
G02X1644758Y120142I0J3503D01*
G03X1644620Y120243I-176J-95D01*
G01X1644318Y120302D01*
G03X1644153Y120261I-39J-196D01*
G02X1641932Y119466I-2222J2708D01*
G02X1638429Y122969I0J3503D01*
G02X1641930Y126472I3503J0D01*
G01X1641934D01*
G02X1641968Y126471I-86J-3501D01*
G02X1644917Y128084I2949J-1889D01*
G02X1647640Y126784I0J-3502D01*
G01X1647671Y126746D01*
X1647761Y126707D01*
X1648188Y126740D01*
X1648272Y126793D01*
X1648296Y126835D01*
G02X1651325Y128578I3029J-1760D01*
G37*
G36*
G01X1710941Y116941D02*
Y117059D01*
G03X1710891Y117190I-200J-1D01*
G02X1710022Y119500I2634J2309D01*
G02X1717026I3502J0D01*
G02X1716157Y117190I-3503J-1D01*
G03X1716107Y117059I150J-132D01*
G01Y116942D01*
G03X1716157Y116810I200J0D01*
G02X1716915Y115377I-2633J-2310D01*
G03X1717027Y115245I193J51D01*
G01X1717353Y115098D01*
X1717444Y115100D01*
X1717484Y115120D01*
G02X1719075Y115502I1591J-3120D01*
G02X1722578Y112000I1J-3502D01*
G02X1721665Y109643I-3503J1D01*
G03Y109373I148J-135D01*
G02X1722578Y107016I-2590J-2358D01*
G02X1719075Y103514I-3503J1D01*
G02X1715687Y106127I0J3503D01*
G01X1715676Y106171D01*
X1715617Y106239D01*
X1715292Y106386D01*
G03X1715119Y106381I-81J-183D01*
G01X1715118D01*
G02X1713527Y105998I-1593J3119D01*
G01X1713524D01*
G02X1710022Y109500I0J3502D01*
G02X1710891Y111810I3503J1D01*
G03X1710941Y111941I-150J132D01*
G01Y112059D01*
G03X1710891Y112190I-200J-1D01*
G02Y116810I2634J2310D01*
G03X1710941Y116941I-150J132D01*
G37*
G36*
G01X1696600Y115498D02*
G02X1700102Y119000I0J3502D01*
G02X1699993Y118129I-3503J-4D01*
G01X1699980Y118078D01*
X1700007Y117976D01*
X1700326Y117657D01*
X1700428Y117630D01*
X1700479Y117643D01*
G02X1701350Y117752I867J-3394D01*
G02X1697848Y114250I0J-3502D01*
G02X1697957Y115121I3503J4D01*
G01X1697970Y115172D01*
X1697943Y115274D01*
X1697624Y115593D01*
X1697522Y115620D01*
X1697471Y115607D01*
G02X1696600Y115498I-867J3394D01*
G37*
G36*
G01X1618792Y114940D02*
G02X1619348Y116832I3503J-2D01*
G03Y117048I-169J108D01*
G02X1618792Y118940I2947J1894D01*
G02X1625798I3503J0D01*
G02X1625242Y117048I-3503J2D01*
G03Y116832I169J-108D01*
G02X1625798Y114940I-2947J-1894D01*
G02X1618792I-3503J0D01*
G37*
G36*
G01X1629870Y100738D02*
X1629866D01*
G02X1629571Y100751I7J3502D01*
G03X1629539I-16J-200D01*
G02X1629270Y100740I-277J3489D01*
G02X1627656Y101135I1J3500D01*
G03X1627445Y101119I-93J-177D01*
G02X1625370Y100438I-2075J2821D01*
G02Y107442I0J3502D01*
G01X1625372D01*
G02X1626988Y107046I-2J-3502D01*
G03X1627199Y107062I93J177D01*
G02X1628646Y107684I2070J-2822D01*
G03X1628780Y107775I-36J197D01*
G01X1628937Y108025D01*
G03X1628960Y108183I-170J105D01*
G01Y108184D01*
G02X1628834Y109113I3376J931D01*
G01Y109117D01*
G02X1629731Y111458I3503J0D01*
G03X1629779Y111624I-149J133D01*
G01X1629719Y111979D01*
X1629666Y112053D01*
X1629627Y112075D01*
G02X1627820Y115140I1696J3065D01*
G02X1634826I3503J0D01*
G02X1633928Y112799I-3503J1D01*
G01X1633897Y112764D01*
X1633872Y112678D01*
X1633940Y112278D01*
X1633993Y112204D01*
X1634032Y112182D01*
G02X1635838Y109119I-1696J-3064D01*
G01Y109117D01*
G02X1633461Y105800I-3503J0D01*
G01X1633424Y105787D01*
X1633365Y105737D01*
X1633202Y105415D01*
X1633196Y105338D01*
X1633208Y105300D01*
G02X1633372Y104242I-3338J-1059D01*
G01Y104240D01*
G02X1629870Y100738I-3502J0D01*
G37*
G36*
G01X1485918Y117276D02*
G02X1487337Y116975I-2J-3503D01*
G03X1487499I81J183D01*
G02X1488918Y117276I1421J-3202D01*
G02X1490337Y116975I-2J-3503D01*
G03X1490499I81J183D01*
G02X1491918Y117276I1421J-3202D01*
G02X1495420Y113773I-1J-3503D01*
G01Y113771D01*
G02X1495120Y112354I-3502J1D01*
G03Y112192I183J-81D01*
G02X1495420Y110773I-3202J-1418D01*
G02X1495120Y109354I-3502J-1D01*
G03Y109192I183J-81D01*
G02X1495420Y107773I-3202J-1418D01*
G02X1495120Y106354I-3502J-1D01*
G03Y106192I183J-81D01*
G02X1495420Y104773I-3202J-1418D01*
G02X1491918Y101270I-3502J-1D01*
G02X1490499Y101571I2J3503D01*
G03X1490337I-81J-183D01*
G02X1488918Y101270I-1421J3202D01*
G02X1487499Y101571I2J3503D01*
G03X1487337I-81J-183D01*
G02X1485918Y101270I-1421J3202D01*
G02X1484499Y101571I2J3503D01*
G03X1484337I-81J-183D01*
G02X1482918Y101270I-1421J3202D01*
G02X1479416Y104773I1J3503D01*
G01Y104775D01*
G02X1479716Y106192I3502J-1D01*
G03Y106354I-183J81D01*
G02X1479416Y107773I3202J1418D01*
G02X1479716Y109192I3502J1D01*
G03Y109354I-183J81D01*
G02X1479416Y110773I3202J1418D01*
G02X1479716Y112192I3502J1D01*
G03Y112354I-183J81D01*
G02X1479416Y113773I3202J1418D01*
G02X1482918Y117276I3502J1D01*
G02X1484337Y116975I-2J-3503D01*
G03X1484499I81J183D01*
G02X1485918Y117276I1421J-3202D01*
G37*
G36*
G01X1527100Y104998D02*
G02X1523631Y108014I0J3503D01*
G03X1523496Y108176I-198J-28D01*
G02X1521098Y111500I1105J3324D01*
G02X1524600Y115002I3502J0D01*
G02X1528069Y111986I0J-3503D01*
G03X1528204Y111824I198J28D01*
G02X1530602Y108500I-1105J-3324D01*
G02X1527100Y104998I-3502J0D01*
G37*
G36*
G01X1662000Y109502D02*
G02Y102498I0J-3502D01*
G01X1661999D01*
G02X1661058Y102627I1J3502D01*
G01X1661057D01*
G03X1660886Y102596I-53J-193D01*
G01X1660632Y102410D01*
G03X1660550Y102257I118J-162D01*
G01Y102256D01*
G02X1657050Y98878I-3500J124D01*
G01X1657049D01*
G02X1655113Y99462I0J3502D01*
G01X1655070Y99490D01*
X1654969Y99499D01*
X1654614Y99342D01*
G03X1654497Y99190I81J-183D01*
G02X1651037Y96232I-3460J545D01*
G02X1648036Y97928I0J3503D01*
G03X1647820Y98020I-171J-103D01*
G02X1647037Y97932I-780J3414D01*
G02X1645381Y98347I-2J3502D01*
G03X1645193I-94J-176D01*
G02X1643537Y97932I-1654J3087D01*
G02X1641881Y98347I-2J3502D01*
G03X1641693I-94J-176D01*
G02X1640039Y97932I-1654J3087D01*
G01X1640037D01*
G02X1636545Y101165I0J3502D01*
G03X1636464Y101311I-200J-15D01*
G02X1635034Y104134I2071J2823D01*
G02X1638537Y107636I3503J-1D01*
G01X1638539D01*
G02X1640193Y107221I0J-3502D01*
G03X1640381I94J176D01*
G02X1642037Y107636I1654J-3087D01*
G02X1643693Y107221I2J-3502D01*
G03X1643881I94J176D01*
G02X1645535Y107636I1654J-3087D01*
G01X1645537D01*
G02X1649029Y104403I0J-3502D01*
G03X1649110Y104257I200J15D01*
G02X1650038Y103240I-2073J-2823D01*
G03X1650254Y103148I171J103D01*
G02X1651037Y103236I780J-3414D01*
G02X1652974Y102652I1J-3502D01*
G01X1653017Y102624D01*
X1653118Y102615D01*
X1653473Y102772D01*
G03X1653590Y102924I-81J183D01*
G02X1657050Y105882I3460J-545D01*
G01X1657051D01*
G02X1657992Y105753I-1J-3502D01*
G01X1657993D01*
G03X1658164Y105784I53J193D01*
G01X1658418Y105970D01*
G03X1658500Y106123I-118J162D01*
G01Y106124D01*
G02X1662000Y109502I3500J-124D01*
G37*
G36*
G01X1715172Y99000D02*
G02X1718675Y102502I3503J-1D01*
G02X1722133Y99554I0J-3502D01*
G03X1722296Y99389I197J32D01*
G02X1725188Y95940I-611J-3449D01*
G02X1722140Y92467I-3503J0D01*
G03X1721978Y92335I27J-198D01*
G02X1721160Y91032I-3303J1165D01*
G01X1721159Y91031D01*
G03X1721102Y90891I143J-140D01*
G01Y90609D01*
G03X1721159Y90469I200J0D01*
G01X1721160Y90468D01*
G02X1722178Y88000I-2485J-2469D01*
G02X1715172I-3503J0D01*
G02X1716190Y90468I3503J-1D01*
G01X1716191Y90469D01*
G03X1716248Y90609I-143J140D01*
G01Y90891D01*
G03X1716191Y91031I-200J0D01*
G01X1716190Y91032D01*
G02X1715172Y93500I2485J2469D01*
G02X1716190Y95968I3503J-1D01*
G01X1716191Y95969D01*
G03X1716248Y96109I-143J140D01*
G01Y96391D01*
G03X1716191Y96531I-200J0D01*
G01X1716190Y96532D01*
G02X1715172Y99000I2485J2469D01*
G37*
G36*
G01X1531600Y93438D02*
G02X1528415Y95483I0J3503D01*
G03X1528172Y95591I-182J-82D01*
G02X1527100Y95422I-1075J3334D01*
G02Y102428I0J3503D01*
G02X1530285Y100383I0J-3503D01*
G03X1530528Y100275I182J82D01*
G02X1531600Y100444I1075J-3334D01*
G02Y93438I0J-3503D01*
G37*
G36*
G01X1602100Y92502D02*
G02X1603992Y91947I0J-3502D01*
G03X1604208I108J168D01*
G02X1606100Y92502I1892J-2947D01*
G01X1606102D01*
G02X1607519Y92202I-1J-3502D01*
G03X1607681I81J183D01*
G02X1609098Y92502I1418J-3202D01*
G01X1609100D01*
G02X1612602Y89000I0J-3502D01*
G01Y88998D01*
G02X1612187Y87344I-3502J0D01*
G03Y87156I176J-94D01*
G02X1612602Y85500I-3087J-1654D01*
G01Y85430D01*
Y85426D01*
X1612601Y85366D01*
X1612667Y85264D01*
X1613126Y85072D01*
X1613245Y85097D01*
X1613288Y85141D01*
G02X1615800Y86202I2511J-2441D01*
G02X1617219Y85902I1J-3502D01*
G03X1617381I81J183D01*
G02X1618798Y86202I1418J-3202D01*
G01X1618800D01*
G02X1622302Y82700I0J-3502D01*
G01Y82698D01*
G02X1622002Y81281I-3502J1D01*
G03Y81119I183J-81D01*
G02X1622302Y79700I-3202J-1418D01*
G02X1622002Y78281I-3502J-1D01*
G03Y78119I183J-81D01*
G02X1622302Y76702I-3202J-1418D01*
G01Y76700D01*
G02X1618800Y73198I-3502J0D01*
G01X1618798D01*
G02X1617381Y73498I1J3502D01*
G03X1617219I-81J-183D01*
G02X1615802Y73198I-1418J3202D01*
G01X1615800D01*
G02X1612298Y76700I0J3502D01*
G01Y76702D01*
G02X1612598Y78119I3502J-1D01*
G03Y78281I-183J81D01*
G02X1612316Y79341I3202J1419D01*
G03X1612182Y79510I-199J-20D01*
G01X1611838Y79628D01*
G03X1611630Y79578I-65J-189D01*
G01X1611629Y79577D01*
G02X1609100Y78498I-2529J2424D01*
G01X1609098D01*
G02X1607681Y78798I1J3502D01*
G03X1607519I-81J-183D01*
G02X1606102Y78498I-1418J3202D01*
G01X1606100D01*
G02X1604208Y79053I0J3502D01*
G03X1603992I-108J-168D01*
G02X1602100Y78498I-1892J2947D01*
G02X1598598Y82000I0J3502D01*
G01Y82002D01*
G02X1599013Y83656I3502J0D01*
G03Y83844I-176J94D01*
G02X1598598Y85500I3087J1654D01*
G02X1599013Y87156I3502J2D01*
G03Y87344I-176J94D01*
G02X1598598Y88998I3087J1654D01*
G01Y89000D01*
G02X1602100Y92502I3502J0D01*
G37*
G36*
G01X1486498Y80500D02*
Y80502D01*
G02X1486913Y82156I3502J0D01*
G03Y82344I-176J94D01*
G02X1486498Y83998I3087J1654D01*
G01Y84000D01*
G02X1490000Y87502I3502J0D01*
G01X1490002D01*
G02X1492519Y86434I-1J-3502D01*
G03X1492775Y86407I144J139D01*
G02X1494728Y87002I1953J-2908D01*
G02Y79998I0J-3502D01*
G02X1493915Y80094I1J3502D01*
G01X1493912D01*
G03X1493761Y80068I-44J-195D01*
G01X1493483Y79893D01*
X1493437Y79826D01*
X1493429Y79786D01*
G02X1490000Y76998I-3429J715D01*
G02X1486498Y80500I0J3502D01*
G37*
G36*
G01X1644298Y80200D02*
G02X1644598Y81619I3502J1D01*
G03Y81781I-183J81D01*
G02X1644298Y83198I3202J1418D01*
G01Y83200D01*
G02X1651302I3502J0D01*
G01Y83198D01*
G02X1651002Y81781I-3502J1D01*
G03Y81619I183J-81D01*
G02X1651302Y80200I-3202J-1418D01*
G02X1651002Y78781I-3502J-1D01*
G03Y78619I183J-81D01*
G02X1651302Y77202I-3202J-1418D01*
G01Y77200D01*
G02X1644298I-3502J0D01*
G01Y77202D01*
G02X1644598Y78619I3502J-1D01*
G03Y78781I-183J81D01*
G02X1644298Y80200I3202J1418D01*
G37*
G36*
G01X317000Y77978D02*
G02X319128Y77256I-2J-3502D01*
G03X319372I122J159D01*
G02X320499Y77831I2129J-2781D01*
G03X320634Y77968I-57J192D01*
G02X324000Y80502I3366J-969D01*
G02X327418Y77765I0J-3503D01*
G03X327526Y77629I195J44D01*
G02X328128Y77257I-1531J-3150D01*
G03X328372I122J159D01*
G02X330499Y77978I2128J-2781D01*
G01X330500D01*
G02Y70974I0J-3502D01*
G01X330499D01*
G02X328372Y71695I1J3502D01*
G03X328128I-122J-159D01*
G02X326000Y70974I-2128J2781D01*
G02X323873Y71694I0J3502D01*
G03X323630I-121J-159D01*
G02X321500Y70972I-2130J2781D01*
G02X319372Y71694I2J3502D01*
G03X319128I-122J-159D01*
G02X317000Y70972I-2130J2780D01*
G02Y77978I0J3503D01*
G37*
G36*
G01X1695500Y72998D02*
X1695498D01*
G02X1693782Y73448I1J3502D01*
G03X1693593Y73451I-97J-175D01*
G02X1692001Y73068I-1592J3119D01*
G01X1692000D01*
G02Y80072I0J3502D01*
G01X1692002D01*
G02X1693718Y79622I-1J-3502D01*
G03X1693907Y79619I97J175D01*
G02X1695499Y80002I1592J-3119D01*
G01X1695500D01*
G02Y72998I0J-3502D01*
G37*
G36*
G01X1503728Y70974D02*
G02X1501585Y71706I0J3503D01*
G03X1501342Y71707I-122J-158D01*
G02X1499230Y70998I-2113J2793D01*
G01X1499228D01*
G02Y78002I0J3502D01*
G01X1499231D01*
G02X1501371Y77271I-2J-3503D01*
G03X1501614Y77270I122J158D01*
G02X1503728Y77980I2114J-2793D01*
G02Y70974I0J-3503D01*
G37*
G36*
G01X1602100Y73002D02*
G02X1603992Y72447I0J-3502D01*
G03X1604208I108J168D01*
G02X1606100Y73002I1892J-2947D01*
G01X1606102D01*
G02X1607519Y72702I-1J-3502D01*
G03X1607681I81J183D01*
G02X1609098Y73002I1418J-3202D01*
G01X1609100D01*
G02X1612602Y69500I0J-3502D01*
G01Y69498D01*
G02X1612187Y67844I-3502J0D01*
G03Y67656I176J-94D01*
G02X1612602Y66000I-3087J-1654D01*
G02X1612187Y64344I-3502J-2D01*
G03Y64156I176J-94D01*
G02X1612602Y62502I-3087J-1654D01*
G01Y62500D01*
G02X1609100Y58998I-3502J0D01*
G01X1609098D01*
G02X1607681Y59298I1J3502D01*
G03X1607519I-81J-183D01*
G02X1606102Y58998I-1418J3202D01*
G01X1606100D01*
G02X1604208Y59553I0J3502D01*
G03X1603992I-108J-168D01*
G02X1602100Y58998I-1892J2947D01*
G02X1598598Y62500I0J3502D01*
G01Y62502D01*
G02X1599013Y64156I3502J0D01*
G03Y64344I-176J94D01*
G02X1598598Y66000I3087J1654D01*
G02X1599013Y67656I3502J2D01*
G03Y67844I-176J94D01*
G02X1598598Y69498I3087J1654D01*
G01Y69500D01*
G02X1602100Y73002I3502J0D01*
G37*
G36*
G01X1494554Y63002D02*
G02X1492600Y63719I175J3498D01*
G03X1492356I-122J-159D01*
G02X1490229Y62998I-2128J2781D01*
G01X1490228D01*
G02Y70002I0J3502D01*
G01X1490229D01*
G02X1492356Y69281I-1J-3502D01*
G03X1492600I122J159D01*
G02X1494727Y70002I2128J-2781D01*
G01X1494728D01*
G02X1498167Y67160I0J-3502D01*
G03X1498354Y66998I196J38D01*
G02X1501063Y65489I-174J-3498D01*
G01X1501095Y65442D01*
X1501199Y65397D01*
X1501611Y65456D01*
G03X1501772Y65591I-29J198D01*
G01Y65592D01*
G02X1505100Y68002I3328J-1093D01*
G02Y60998I0J-3502D01*
G02X1502217Y62511I0J3503D01*
G01X1502185Y62558D01*
X1502081Y62603D01*
X1501669Y62544D01*
G03X1501508Y62409I29J-198D01*
G01Y62408D01*
G02X1498180Y59998I-3328J1093D01*
G02X1494741Y62840I0J3502D01*
G03X1494554Y63002I-196J-38D01*
G37*
G36*
G01X313498Y64500D02*
G02X317000Y68002I3502J0D01*
G01X317001D01*
G02X318066Y67836I0J-3502D01*
G03X318309Y67944I61J191D01*
G02X321500Y70002I3191J-1445D01*
G02X324813Y67636I0J-3503D01*
G03X325007Y67501I189J65D01*
G02X325100Y67502I84J-3501D01*
G02Y60498I0J-3502D01*
G01X325096D01*
G02X323842Y60731I2J3502D01*
G03X323621Y60677I-71J-187D01*
G02X321000Y59498I-2621J2324D01*
G02X320769Y59505I-9J3502D01*
G01X320720Y59508D01*
X320631Y59469D01*
X320363Y59136D01*
X320345Y59040D01*
X320359Y58993D01*
G02X320502Y58005I-3359J-991D01*
G01Y58000D01*
G02X313498I-3502J0D01*
G01Y58001D01*
G02X315061Y60917I3502J0D01*
G01X315102Y60945D01*
X315150Y61033D01*
Y61467D01*
X315102Y61555D01*
X315061Y61583D01*
G02X313498Y64499I1939J2916D01*
G01Y64500D01*
G37*
G36*
G01X1419310Y43984D02*
G02X1420729Y43683I-2J-3503D01*
G03X1420891I81J183D01*
G02X1422310Y43984I1421J-3202D01*
G02X1423729Y43683I-2J-3503D01*
G03X1423891I81J183D01*
G02X1425310Y43984I1421J-3202D01*
G02Y36978I0J-3503D01*
G02X1423891Y37279I2J3503D01*
G03X1423729I-81J-183D01*
G02X1422310Y36978I-1421J3202D01*
G02X1420891Y37279I2J3503D01*
G03X1420729I-81J-183D01*
G02X1419310Y36978I-1421J3202D01*
G02X1417891Y37279I2J3503D01*
G03X1417729I-81J-183D01*
G02X1416310Y36978I-1421J3202D01*
G02Y43984I0J3503D01*
G02X1417729Y43683I-2J-3503D01*
G03X1417891I81J183D01*
G02X1419310Y43984I1421J-3202D01*
G37*
G36*
G01X317766Y42714D02*
G02X319185Y42413I-2J-3503D01*
G03X319347I81J183D01*
G02X320766Y42714I1421J-3202D01*
G02X322185Y42413I-2J-3503D01*
G03X322347I81J183D01*
G02X323766Y42714I1421J-3202D01*
G02Y35708I0J-3503D01*
G02X322347Y36009I2J3503D01*
G03X322185I-81J-183D01*
G02X320766Y35708I-1421J3202D01*
G02X319347Y36009I2J3503D01*
G03X319185I-81J-183D01*
G02X317766Y35708I-1421J3202D01*
G02X316347Y36009I2J3503D01*
G03X316185I-81J-183D01*
G02X314766Y35708I-1421J3202D01*
G02Y42714I0J3503D01*
G02X316185Y42413I-2J-3503D01*
G03X316347I81J183D01*
G02X317766Y42714I1421J-3202D01*
G37*
G36*
G01X1352310Y42396D02*
G02X1353729Y42095I-2J-3503D01*
G03X1353891I81J183D01*
G02X1355310Y42396I1421J-3202D01*
G02X1356729Y42095I-2J-3503D01*
G03X1356891I81J183D01*
G02X1358310Y42396I1421J-3202D01*
G02Y35390I0J-3503D01*
G02X1356891Y35691I2J3503D01*
G03X1356729I-81J-183D01*
G02X1355310Y35390I-1421J3202D01*
G02X1353891Y35691I2J3503D01*
G03X1353729I-81J-183D01*
G02X1352310Y35390I-1421J3202D01*
G02X1350891Y35691I2J3503D01*
G03X1350729I-81J-183D01*
G02X1349310Y35390I-1421J3202D01*
G02Y42396I0J3503D01*
G02X1350729Y42095I-2J-3503D01*
G03X1350891I81J183D01*
G02X1352310Y42396I1421J-3202D01*
G37*
G36*
G01X1310366Y41984D02*
G02X1311785Y41684I1J-3502D01*
G03X1311947I81J183D01*
G02X1313366Y41984I1418J-3202D01*
G02X1314785Y41684I1J-3502D01*
G03X1314947I81J183D01*
G02X1316364Y41984I1418J-3202D01*
G01X1316366D01*
G02Y34980I0J-3502D01*
G01X1316364D01*
G02X1314947Y35280I1J3502D01*
G03X1314785I-81J-183D01*
G02X1313366Y34980I-1418J3202D01*
G02X1311947Y35280I-1J3502D01*
G03X1311785I-81J-183D01*
G02X1310366Y34980I-1418J3202D01*
G02X1308947Y35280I-1J3502D01*
G03X1308785I-81J-183D01*
G02X1307368Y34980I-1418J3202D01*
G01X1307366D01*
G02Y41984I0J3502D01*
G01X1307368D01*
G02X1308785Y41684I-1J-3502D01*
G03X1308947I81J183D01*
G02X1310366Y41984I1418J-3202D01*
G37*
G36*
G01X1431417Y23264D02*
G02X1436375Y21472I1J-7753D01*
G03X1436700Y21593I128J154D01*
G02X1441417Y25606I4717J-766D01*
G02Y16048I0J-4779D01*
G02X1439413Y16489I1J4779D01*
G03X1439130Y16288I-84J-181D01*
G02X1439169Y15512I-7713J-777D01*
G02X1431417Y23264I-7752J0D01*
G37*
G36*
G01X1726171Y160576D02*
X1726018Y160913D01*
X1725959Y160968D01*
X1725920Y160982D01*
G02X1723598Y164280I1181J3298D01*
G02X1730602I3502J0D01*
G02X1730354Y162984I-3502J-2D01*
G01X1730339Y162946D01*
X1730340Y162865D01*
X1730493Y162528D01*
X1730552Y162473D01*
X1730591Y162459D01*
G02X1732914Y159161I-1180J-3298D01*
G02X1729411Y155658I-3503J0D01*
G02X1729293Y155660I0J3503D01*
G01X1729236Y155662D01*
X1729138Y155606D01*
X1728914Y155189D01*
X1728921Y155076D01*
X1728954Y155029D01*
G02X1729602Y153000I-2855J-2030D01*
G02X1722596I-3503J0D01*
G02X1722597Y153055I3502J-36D01*
G01X1722598Y153097D01*
X1722567Y153172D01*
X1722300Y153434D01*
X1722225Y153463D01*
X1722183Y153462D01*
G02X1722063Y153460I-118J3500D01*
G02X1719329Y154773I0J3503D01*
G03X1719088Y154829I-156J-125D01*
G02X1718999Y154789I-1480J3174D01*
G01X1718963Y154773D01*
X1718910Y154719D01*
X1718773Y154390D01*
X1718772Y154314D01*
X1718787Y154277D01*
G02X1719028Y153000I-3263J-1277D01*
G02X1715525Y149498I-3503J1D01*
G02X1713858Y149920I0J3502D01*
G03X1713667I-96J-176D01*
G02X1712000Y149498I-1667J3080D01*
G02X1708498Y153000I0J3502D01*
G02X1708701Y154177I3502J2D01*
G01X1708715Y154215D01*
X1708711Y154295D01*
X1708553Y154624D01*
X1708494Y154677D01*
X1708455Y154690D01*
G02X1706098Y158000I1146J3310D01*
G02X1713102I3502J0D01*
G02X1712899Y156823I-3502J-2D01*
G01X1712885Y156785D01*
X1712889Y156705D01*
X1713047Y156376D01*
X1713106Y156323D01*
X1713145Y156310D01*
G02X1713667Y156080I-1146J-3309D01*
G03X1713858I96J176D01*
G02X1714126Y156211I1671J-3078D01*
G01X1714162Y156227D01*
X1714215Y156281D01*
X1714352Y156610D01*
X1714353Y156686D01*
X1714338Y156723D01*
G02X1714098Y158000I3263J1274D01*
G02X1717600Y161502I3502J0D01*
G02X1720334Y160189I0J-3503D01*
G03X1720575Y160133I156J125D01*
G02X1722063Y160464I1486J-3171D01*
G02X1725566Y156962I1J-3502D01*
G02X1725565Y156907I-3502J36D01*
G01X1725564Y156865D01*
X1725595Y156790D01*
X1725862Y156528D01*
X1725937Y156499D01*
X1725979Y156500D01*
G02X1726099Y156502I118J-3500D01*
G02X1726217Y156501I29J-3502D01*
G01X1726274Y156499D01*
X1726372Y156555D01*
X1726596Y156972D01*
X1726589Y157085D01*
X1726556Y157132D01*
G02X1725908Y159161I2855J2030D01*
G02X1726157Y160457I3503J-1D01*
G01X1726172Y160495D01*
X1726171Y160576D01*
G37*
G36*
G01X1730445Y171934D02*
X1730330Y171962D01*
G03X1730184Y171943I-49J-194D01*
G02X1728475Y171498I-1708J3057D01*
G02Y178502I0J3502D01*
G02X1731410Y176911I0J-3503D01*
G03X1731530Y176826I168J109D01*
G01X1731645Y176798D01*
G03X1731791Y176817I49J194D01*
G02X1733500Y177262I1708J-3057D01*
G02Y170258I0J-3502D01*
G02X1730565Y171849I0J3503D01*
G03X1730445Y171934I-168J-109D01*
G37*
G36*
G01X1723086Y177389D02*
G02X1724026Y175000I-2563J-2388D01*
G02X1717022I-3502J0D01*
G02X1717561Y176868I3502J1D01*
G03X1717538Y177111I-169J107D01*
G02X1716598Y179500I2563J2388D01*
G02X1723602I3502J0D01*
G02X1723063Y177632I-3502J-1D01*
G03X1723086Y177389I169J-107D01*
G37*
G36*
G01X1683549Y183568D02*
X1683548Y183931D01*
X1683519Y184003D01*
X1683490Y184031D01*
G02X1682472Y186500I2485J2469D01*
G02X1685975Y190002I3503J-1D01*
G02X1689304Y187588I0J-3502D01*
G03X1689419Y187465I190J62D01*
G02X1691602Y184220I-1320J-3245D01*
G02X1689478Y181000I-3503J0D01*
G02X1688461Y178532I-3503J0D01*
G01X1688433Y178503D01*
X1688403Y178431D01*
Y178069D01*
X1688433Y177997D01*
X1688461Y177968D01*
G02X1689357Y176415I-2485J-2469D01*
G03X1689472Y176283I193J52D01*
G02X1691602Y173060I-1372J-3222D01*
G02X1689582Y169887I-3502J0D01*
G03X1689467Y169721I85J-181D01*
G02X1688461Y167532I-3491J279D01*
G01X1688433Y167503D01*
X1688403Y167431D01*
Y167069D01*
X1688433Y166997D01*
X1688461Y166968D01*
G02X1689357Y165415I-2485J-2469D01*
G03X1689472Y165283I193J52D01*
G02X1691602Y162060I-1372J-3222D01*
G02X1689582Y158887I-3502J0D01*
G03X1689467Y158721I85J-181D01*
G02X1688461Y156532I-3491J279D01*
G01X1688433Y156503D01*
X1688403Y156431D01*
Y156069D01*
X1688433Y155997D01*
X1688461Y155968D01*
G02Y151032I-2486J-2468D01*
G01X1688433Y151003D01*
X1688403Y150931D01*
Y150569D01*
X1688433Y150497D01*
X1688461Y150468D01*
G02X1689357Y148915I-2485J-2469D01*
G03X1689472Y148783I193J52D01*
G02X1691602Y145560I-1372J-3222D01*
G02X1688100Y142058I-3502J0D01*
G02X1684719Y144645I0J3503D01*
G03X1684604Y144777I-193J-52D01*
G02X1682474Y148000I1372J3222D01*
G02X1683491Y150468I3503J0D01*
G01X1683519Y150497D01*
X1683549Y150569D01*
Y150931D01*
X1683519Y151003D01*
X1683491Y151032D01*
G02X1682474Y153500I2486J2468D01*
G01Y153523D01*
G03X1682393Y153685I-200J1D01*
G02X1682359Y153710I2058J2834D01*
G03X1682117I-121J-160D01*
G02X1680000Y152998I-2117J2791D01*
G02X1676498Y156467I0J3502D01*
G03X1676441Y156605I-200J-2D01*
G01X1676357Y156690D01*
G03X1676221Y156751I-144J-139D01*
G02X1672848Y160251I129J3500D01*
G02X1676350Y163754I3502J1D01*
G02X1679852Y160284I0J-3502D01*
G03X1679909Y160146I200J2D01*
G01X1679993Y160061D01*
G03X1680129Y160000I144J139D01*
G02X1682117Y159290I-129J-3500D01*
G03X1682359I121J160D01*
G02X1682425Y159339I2121J-2787D01*
G03X1682506Y159474I-117J162D01*
G02X1683491Y161468I3470J-474D01*
G01X1683519Y161497D01*
X1683549Y161569D01*
Y161931D01*
X1683519Y162003D01*
X1683491Y162032D01*
G02Y166968I2486J2468D01*
G01X1683519Y166997D01*
X1683549Y167069D01*
Y167431D01*
X1683519Y167503D01*
X1683491Y167532D01*
G02Y172468I2486J2468D01*
G01X1683519Y172497D01*
X1683549Y172569D01*
Y172931D01*
X1683519Y173003D01*
X1683491Y173032D01*
G02Y177968I2486J2468D01*
G01X1683519Y177997D01*
X1683549Y178069D01*
Y178431D01*
X1683519Y178503D01*
X1683491Y178532D01*
G02X1682474Y181000I2486J2468D01*
G02X1683490Y183468I3503J1D01*
G01X1683519Y183496D01*
X1683549Y183568D01*
G37*
G36*
G01X1719705Y201505D02*
X1719698Y201938D01*
X1719649Y202026D01*
X1719607Y202053D01*
G02X1717998Y205000I1894J2947D01*
G02X1721500Y208502I3502J0D01*
G02X1722813Y208247I1J-3502D01*
G03X1722993Y208262I75J185D01*
G02X1724824Y208778I1830J-2986D01*
G02Y201774I0J-3502D01*
G02X1723511Y202029I-1J3502D01*
G03X1723331Y202014I-75J-185D01*
G02X1723322Y202009I-1704J3057D01*
G03X1723226Y201835I104J-171D01*
G01X1723228Y201717D01*
G03X1723329Y201546I200J3D01*
G02X1725102Y198500I-1730J-3046D01*
G02X1724623Y196731I-3502J-1D01*
G03Y196529I173J-101D01*
G02X1725102Y194760I-3023J-1768D01*
G02X1718098I-3502J0D01*
G02X1718577Y196529I3502J1D01*
G03Y196731I-173J101D01*
G02X1718098Y198500I3023J1768D01*
G02X1719617Y201387I3503J0D01*
G01X1719658Y201416D01*
X1719705Y201505D01*
G37*
G36*
G01X1705684Y204830D02*
G02X1708102Y201500I-1084J-3330D01*
G02X1701098I-3502J0D01*
G02X1701127Y201954I3502J4D01*
G03X1700991Y202170I-198J26D01*
G02X1698572Y205500I1083J3331D01*
G02X1705578I3503J0D01*
G02X1705548Y205046I-3503J3D01*
G03X1705684Y204830I198J-26D01*
G37*
G36*
G01X1708618Y189544D02*
G02X1711025Y190502I2407J-2545D01*
G02X1712515Y190170I2J-3502D01*
G03X1712685I85J181D01*
G02X1714175Y190502I1488J-3170D01*
G02Y183498I0J-3502D01*
G02X1712685Y183830I-2J3502D01*
G03X1712515I-85J-181D01*
G02X1711025Y183498I-1488J3170D01*
G02X1709246Y183983I-1J3502D01*
G03X1709007Y183956I-102J-172D01*
G02X1706600Y182998I-2407J2545D01*
G02X1705049Y183360I0J3502D01*
G01X1704995Y183386D01*
X1704880Y183373D01*
X1704506Y183067D01*
X1704470Y182956D01*
X1704485Y182898D01*
G02X1704602Y182000I-3385J-898D01*
G02X1704187Y180345I-3502J-1D01*
G03Y180155I176J-95D01*
G02X1704602Y178500I-3087J-1654D01*
G02X1703137Y175651I-3503J0D01*
G01X1703088Y175616D01*
X1703046Y175505D01*
X1703148Y175029D01*
X1703232Y174946D01*
X1703291Y174934D01*
G02X1706102Y171500I-692J-3434D01*
G02X1703220Y168053I-3502J0D01*
G01X1703161Y168042D01*
X1703074Y167959D01*
X1702965Y167483D01*
X1703007Y167371D01*
X1703056Y167335D01*
G02X1704502Y164500I-2056J-2835D01*
G02X1703485Y162032I-3503J0D01*
G01X1703457Y162003D01*
X1703427Y161931D01*
Y161569D01*
X1703457Y161497D01*
X1703485Y161468D01*
G02X1704502Y159000I-2486J-2468D01*
G02X1701467Y155529I-3502J0D01*
G01X1701420Y155522D01*
X1701342Y155469D01*
X1701141Y155103D01*
X1701137Y155009D01*
X1701157Y154965D01*
G02X1701478Y153500I-3181J-1465D01*
G02X1700461Y151032I-3503J0D01*
G01X1700433Y151003D01*
X1700403Y150931D01*
Y150569D01*
X1700433Y150497D01*
X1700461Y150468D01*
G02X1701478Y148000I-2486J-2468D01*
G02X1694474I-3502J0D01*
G02X1695491Y150468I3503J0D01*
G01X1695519Y150497D01*
X1695549Y150569D01*
Y150931D01*
X1695519Y151003D01*
X1695491Y151032D01*
G02Y155968I2486J2468D01*
G01X1695519Y155997D01*
X1695549Y156069D01*
Y156431D01*
X1695519Y156503D01*
X1695491Y156532D01*
G02Y161468I2486J2468D01*
G01X1695519Y161497D01*
X1695549Y161569D01*
Y161931D01*
X1695519Y162003D01*
X1695491Y162032D01*
G02Y166968I2486J2468D01*
G01X1695519Y166997D01*
X1695549Y167069D01*
Y167431D01*
X1695519Y167503D01*
X1695491Y167532D01*
G02Y172468I2486J2468D01*
G01X1695519Y172497D01*
X1695549Y172569D01*
Y172931D01*
X1695519Y173003D01*
X1695491Y173032D01*
G02X1694474Y175500I2486J2468D01*
G02X1695490Y177968I3503J1D01*
G01X1695519Y177996D01*
X1695549Y178068D01*
X1695548Y178431D01*
X1695519Y178503D01*
X1695490Y178531D01*
G02X1694472Y181000I2485J2469D01*
G02X1697975Y184502I3503J-1D01*
G02X1698496Y184464I6J-3502D01*
G03X1698665Y184518I30J197D01*
G02X1701100Y185502I2434J-2518D01*
G02X1702651Y185140I0J-3502D01*
G01X1702705Y185114D01*
X1702820Y185127D01*
X1703194Y185433D01*
X1703230Y185544D01*
X1703215Y185602D01*
G02X1703098Y186500I3385J898D01*
G02X1706600Y190002I3502J0D01*
G02X1708379Y189517I1J-3502D01*
G03X1708618Y189544I102J172D01*
G37*
G36*
G01X706684Y279998D02*
X706682D01*
G02X704934Y280466I1J3502D01*
G03X704734I-100J-173D01*
G02X702986Y279998I-1749J3034D01*
G01X702984D01*
G02Y287002I0J3502D01*
G01X702986D01*
G02X704734Y286534I-1J-3502D01*
G03X704934I100J173D01*
G02X706682Y287002I1749J-3034D01*
G01X706684D01*
G02Y279998I0J-3502D01*
G37*
G36*
G01Y268898D02*
X706682D01*
G02X704934Y269366I1J3502D01*
G03X704734I-100J-173D01*
G02X702986Y268898I-1749J3034D01*
G01X702984D01*
G02Y275902I0J3502D01*
G01X702986D01*
G02X704734Y275434I-1J-3502D01*
G03X704934I100J173D01*
G02X706682Y275902I1749J-3034D01*
G01X706684D01*
G02Y268898I0J-3502D01*
G37*
G36*
G01X710084Y257598D02*
X710081D01*
G02X708618Y257919I2J3502D01*
G03X708450I-84J-182D01*
G02X706987Y257598I-1465J3181D01*
G01X706984D01*
G02Y264602I0J3502D01*
G01X706987D01*
G02X708450Y264281I-2J-3502D01*
G03X708618I84J182D01*
G02X710081Y264602I1465J-3181D01*
G01X710084D01*
G02Y257598I0J-3502D01*
G37*
G36*
G01X1041398Y278600D02*
G02X1048402I3502J0D01*
G02X1046073Y275300I-3502J0D01*
G01X1046031Y275285D01*
X1045969Y275224D01*
X1045846Y274896D01*
G03X1045858Y274728I187J-71D01*
G02X1046302Y273023I-3058J-1707D01*
G01Y273020D01*
G02X1039298I-3502J0D01*
G02X1041627Y276320I3502J0D01*
G01X1041669Y276335D01*
X1041731Y276396D01*
X1041854Y276724D01*
G03X1041842Y276892I-187J71D01*
G02X1041398Y278597I3058J1707D01*
G01Y278600D01*
G37*
G36*
G01X1055300Y287398D02*
X1055297D01*
G02X1053834Y287719I2J3502D01*
G03X1053666I-84J-182D01*
G02X1052203Y287398I-1465J3181D01*
G01X1052200D01*
G02Y294402I0J3502D01*
G01X1052203D01*
G02X1053666Y294081I-2J-3502D01*
G03X1053834I84J182D01*
G02X1055297Y294402I1465J-3181D01*
G01X1055300D01*
G02Y287398I0J-3502D01*
G37*
G36*
G01X1067025Y300478D02*
X1067023D01*
G02X1064310Y301766I1J3503D01*
G03X1064071Y301821I-155J-126D01*
G02X1062602Y301498I-1469J3179D01*
G01X1062600D01*
G02Y308502I0J3502D01*
G01X1062602D01*
G02X1065315Y307214I-1J-3503D01*
G03X1065554Y307159I155J126D01*
G02X1067023Y307482I1469J-3179D01*
G01X1067025D01*
G02X1068515Y307149I-1J-3503D01*
G03X1068685I85J181D01*
G02X1070175Y307482I1491J-3170D01*
G02Y300478I0J-3502D01*
G02X1068685Y300811I1J3503D01*
G03X1068515I-85J-181D01*
G02X1067025Y300478I-1491J3170D01*
G37*
G36*
G01X1126598Y305174D02*
Y305176D01*
G02X1127053Y306901I3502J-1D01*
G03X1127075Y307038I-174J98D01*
G02X1127008Y307717I3435J682D01*
G01Y307720D01*
G02X1134012I3502J0D01*
G01Y307718D01*
G02X1133557Y305993I-3502J1D01*
G03X1133535Y305856I174J-98D01*
G02X1133602Y305177I-3435J-682D01*
G01Y305174D01*
G02X1126598I-3502J0D01*
G37*
G36*
G01X1197534Y318912D02*
Y318914D01*
G02X1201037Y315410I3503J-1D01*
G01X1200968D01*
X1200964D01*
X1200920Y315411D01*
X1200838Y315374D01*
X1200608Y315101D01*
G03X1200565Y314934I153J-129D01*
G02X1200630Y314264I-3438J-672D01*
G01Y314262D01*
G02X1197127Y317766I-3503J1D01*
G01X1197196D01*
X1197200D01*
X1197244Y317765D01*
X1197326Y317802D01*
X1197556Y318075D01*
G03X1197599Y318242I-153J129D01*
G02X1197534Y318912I3438J672D01*
G37*
G36*
G01X1119598Y319500D02*
Y319502D01*
G02X1119898Y320919I3502J-1D01*
G03Y321081I-183J81D01*
G02X1119598Y322498I3202J1418D01*
G01Y322500D01*
G02X1126602I3502J0D01*
G01Y322498D01*
G02X1126302Y321081I-3502J1D01*
G03Y320919I183J-81D01*
G02X1126602Y319502I-3202J-1418D01*
G01Y319500D01*
G02X1119598I-3502J0D01*
G37*
G36*
G01X1254537Y333321D02*
Y333679D01*
G03X1254425Y333859I-200J0D01*
G02X1252472Y337000I1549J3141D01*
G02X1259478I3503J0D01*
G02X1257525Y333859I-3502J0D01*
G03X1257413Y333679I88J-180D01*
G01Y333321D01*
G03X1257525Y333141I200J0D01*
G02X1259478Y330000I-1549J-3141D01*
G02X1252472I-3503J0D01*
G02X1254425Y333141I3502J0D01*
G03X1254537Y333321I-88J180D01*
G37*
G36*
G01X1084241Y342083D02*
X1084359D01*
G03X1084490Y342133I-1J200D01*
G02X1086800Y343002I2309J-2634D01*
G01X1086803D01*
G02X1087983Y342797I-1J-3502D01*
G03X1088117I67J188D01*
G02X1089297Y343002I1181J-3297D01*
G01X1089300D01*
G02Y335998I0J-3502D01*
G01X1089297D01*
G02X1088117Y336203I1J3502D01*
G03X1087983I-67J-188D01*
G02X1086803Y335998I-1181J3297D01*
G01X1086800D01*
G02X1084490Y336867I-1J3503D01*
G03X1084359Y336917I-132J-150D01*
G01X1084241D01*
G03X1084110Y336867I1J-200D01*
G02X1081800Y335998I-2309J2634D01*
G01X1081797D01*
G02X1080617Y336203I1J3502D01*
G03X1080483I-67J-188D01*
G02X1079303Y335998I-1181J3297D01*
G01X1079300D01*
G02X1076832Y337015I0J3503D01*
G01X1076831Y337016D01*
G03X1076691Y337073I-140J-143D01*
G01X1076409D01*
G03X1076269Y337016I0J-200D01*
G01X1076268Y337015D01*
G02X1073800Y335998I-2468J2486D01*
G01X1073797D01*
G02X1072617Y336203I1J3502D01*
G03X1072483I-67J-188D01*
G02X1071303Y335998I-1181J3297D01*
G01X1071300D01*
G02X1068832Y337015I0J3503D01*
G01X1068831Y337016D01*
G03X1068691Y337073I-140J-143D01*
G01X1068409D01*
G03X1068269Y337016I0J-200D01*
G01X1068268Y337015D01*
G02X1065800Y335998I-2468J2486D01*
G01X1065797D01*
G02X1064617Y336203I1J3502D01*
G03X1064483I-67J-188D01*
G02X1063303Y335998I-1181J3297D01*
G01X1063300D01*
G02Y343002I0J3502D01*
G01X1063303D01*
G02X1064483Y342797I-1J-3502D01*
G03X1064617I67J188D01*
G02X1065797Y343002I1181J-3297D01*
G01X1065800D01*
G02X1068268Y341985I0J-3503D01*
G01X1068269Y341984D01*
G03X1068409Y341927I140J143D01*
G01X1068691D01*
G03X1068831Y341984I0J200D01*
G01X1068832Y341985D01*
G02X1071300Y343002I2468J-2486D01*
G01X1071303D01*
G02X1072483Y342797I-1J-3502D01*
G03X1072617I67J188D01*
G02X1073797Y343002I1181J-3297D01*
G01X1073800D01*
G02X1076268Y341985I0J-3503D01*
G01X1076269Y341984D01*
G03X1076409Y341927I140J143D01*
G01X1076691D01*
G03X1076831Y341984I0J200D01*
G01X1076832Y341985D01*
G02X1079300Y343002I2468J-2486D01*
G01X1079303D01*
G02X1080483Y342797I-1J-3502D01*
G03X1080617I67J188D01*
G02X1081797Y343002I1181J-3297D01*
G01X1081800D01*
G02X1084110Y342133I1J-3503D01*
G03X1084241Y342083I132J150D01*
G37*
G36*
G01X1165575Y336998D02*
G02X1164085Y337331I1J3503D01*
G03X1163915I-85J-181D01*
G02X1162425Y336998I-1491J3170D01*
G02Y344002I0J3502D01*
G02X1163915Y343669I-1J-3503D01*
G03X1164085I85J181D01*
G02X1165575Y344002I1491J-3170D01*
G02Y336998I0J-3502D01*
G37*
G36*
G01X1147000Y338998D02*
G02Y346002I0J3502D01*
G01X1147001D01*
G02X1149917Y344439I0J-3502D01*
G01X1149945Y344398D01*
X1150033Y344350D01*
X1150467D01*
X1150555Y344398D01*
X1150583Y344439D01*
G02X1153499Y346002I2916J-1939D01*
G01X1153500D01*
G02Y338998I0J-3502D01*
G01X1153499D01*
G02X1150583Y340561I0J3502D01*
G01X1150555Y340602D01*
X1150467Y340650D01*
X1150033D01*
X1149945Y340602D01*
X1149917Y340561D01*
G02X1147001Y338998I-2916J1939D01*
G01X1147000D01*
G37*
G36*
G01X1527504Y664685D02*
G02X1532283Y669464I4779J0D01*
G02X1535916Y667789I-1J-4779D01*
G03X1536068Y667719I152J130D01*
G01X1536372D01*
G03X1536524Y667789I0J200D01*
G02X1540157Y669464I3634J-3104D01*
G02X1544936Y664685I0J-4779D01*
G02X1543261Y661052I-4779J1D01*
G03X1543191Y660900I130J-152D01*
G01Y660596D01*
G03X1543261Y660444I200J0D01*
G02X1544936Y656811I-3104J-3634D01*
G02X1543261Y653178I-4779J1D01*
G03X1543191Y653026I130J-152D01*
G01Y652722D01*
G03X1543261Y652570I200J0D01*
G02X1544936Y648937I-3104J-3634D01*
G02X1540157Y644158I-4779J0D01*
G02X1536524Y645833I1J4779D01*
G03X1536372Y645903I-152J-130D01*
G01X1536068D01*
G03X1535916Y645833I0J-200D01*
G02X1532283Y644158I-3634J3104D01*
G02X1527504Y648937I0J4779D01*
G02X1529179Y652570I4779J-1D01*
G03X1529249Y652722I-130J152D01*
G01Y653026D01*
G03X1529179Y653178I-200J0D01*
G02X1527504Y656811I3104J3634D01*
G02X1529179Y660444I4779J-1D01*
G03X1529249Y660596I-130J152D01*
G01Y660900D01*
G03X1529179Y661052I-200J0D01*
G02X1527504Y664685I3104J3634D01*
G37*
G36*
G01X1320919Y153245D02*
G02X1320348Y153198I-572J3455D01*
G01X1320346D01*
G02X1323848Y156700I0J3502D01*
G02X1323142Y154591I-3503J0D01*
G03X1323527Y153955I319J-241D01*
G02X1324098Y154002I572J-3455D01*
G01X1324100D01*
G02X1320598Y150500I0J-3502D01*
G02X1321304Y152609I3503J0D01*
G03X1320919Y153245I-319J241D01*
G37*
G36*
G01Y197645D02*
G02X1320348Y197598I-572J3455D01*
G01X1320346D01*
G02X1323848Y201100I0J3502D01*
G02X1323142Y198991I-3503J0D01*
G03X1323527Y198355I319J-241D01*
G02X1324098Y198402I572J-3455D01*
G01X1324100D01*
G02X1320598Y194900I0J-3502D01*
G02X1321304Y197009I3503J0D01*
G03X1320919Y197645I-319J241D01*
G37*
G36*
G01X1139803Y321317D02*
G02X1139598Y322497I3297J1181D01*
G01Y322500D01*
G02X1146602I3502J0D01*
G01Y322497D01*
G02X1146397Y321317I-3502J1D01*
G03Y321183I188J-67D01*
G02X1146602Y320003I-3297J-1181D01*
G01Y320000D01*
G02X1143621Y316536I-3503J0D01*
G01X1143558Y316527D01*
X1143467Y316442D01*
X1143377Y316013D01*
G03X1143466Y315803I196J-41D01*
G01X1143467Y315802D01*
G02X1145102Y312839I-1867J-2963D01*
G02X1138098I-3502J0D01*
G02X1141079Y316303I3503J0D01*
G01X1141142Y316312D01*
X1141233Y316397D01*
X1141323Y316826D01*
G03X1141234Y317036I-196J41D01*
G01X1141233Y317037D01*
G02X1139598Y320000I1867J2963D01*
G01Y320003D01*
G02X1139803Y321183I3502J-1D01*
G03Y321317I-188J67D01*
G37*
G54D59*
X134600Y150000D03*
X408100Y180100D03*
Y224500D03*
X438100Y170000D03*
X428277Y167056D03*
X430608Y211389D03*
X438100Y214500D03*
X441938Y87700D03*
Y132100D03*
Y176500D03*
Y220900D03*
Y265300D03*
Y309700D03*
X691759Y309000D03*
X719500Y315500D03*
X649059Y314000D03*
X396216Y46875D03*
X1624000Y189000D03*
X1652600Y212000D03*
X1668075Y189500D03*
X1631585Y188777D03*
X1809600Y195000D03*
X1778000Y189500D03*
X1769425Y203000D03*
X1800100Y187500D03*
X1754260Y187260D03*
X1738000Y124500D03*
X1667000Y138000D03*
X1658500D03*
X1658000Y179500D03*
X1672050Y181550D03*
X1706100Y92000D03*
X1635000Y152925D03*
X1727200Y104500D03*
X1729411Y143661D03*
X1636600Y173500D03*
X1551000Y96500D03*
X1567500Y67000D03*
X1649197Y132915D03*
X1638707Y132954D03*
X1692600Y135975D03*
X1702525Y129500D03*
X1597100Y145000D03*
X332500Y63300D03*
X1594930Y115000D03*
X1597100Y126000D03*
X1679176Y194760D03*
X1731925Y199000D03*
X1729000Y183500D03*
X1715525Y168500D03*
X623500Y379000D03*
X1024600Y185000D03*
X704240D03*
X1320346Y67900D03*
Y112300D03*
X1334140Y146642D03*
X1332671Y190644D03*
X1320346Y245500D03*
Y289900D03*
X1355100Y160000D03*
X1355000Y204400D03*
X1034360Y254000D03*
X1035750Y294249D03*
X1070525Y243000D03*
X1064600Y324000D03*
X1072600D03*
X1080600D03*
X1157138Y303000D03*
X1157800Y312050D03*
X1154600Y321050D03*
X1141600Y305161D03*
X1244874Y330000D03*
G54D57*
X243785Y390000D03*
X166785D03*
Y310000D03*
X243785Y230000D03*
Y310000D03*
X166785Y230000D03*
Y470000D03*
X243785D03*
X166785Y550000D03*
X243785D03*
X1488500D03*
Y470000D03*
Y230000D03*
X1565500Y470000D03*
X1488500Y390000D03*
X1565500D03*
Y310000D03*
X1488500D03*
X1565500Y230000D03*
Y550000D03*
G54D60*
X260866Y20827D03*
X1451417D03*
G54D64*
X940197Y200984D03*
X822087D03*
G54D58*
X166785Y360472D03*
Y440472D03*
Y520472D03*
X243785Y280472D03*
Y360472D03*
Y440472D03*
Y520472D03*
X166785Y200472D03*
X243785D03*
X166785Y280472D03*
X1488500Y200472D03*
Y280472D03*
Y360472D03*
Y440472D03*
Y520472D03*
X1565500Y200472D03*
Y280472D03*
Y360472D03*
Y440472D03*
Y520472D03*
G54D62*
X1529100Y78500D03*
G54D54*
X207874Y639094D03*
X1524409D03*
G54D65*
X1856772Y360433D03*
X1851457Y220433D03*
G54D56*
X314961Y570866D03*
X393703Y354332D03*
X279529Y62992D03*
X1452757Y62992D03*
X1417325Y570866D03*
X1338585Y354332D03*
G54D55*
X287402Y628465D03*
X1468504D03*
G54D53*
X19685Y766166D03*
X1854331D03*
G54D63*
X940197Y313484D03*
X822087Y88484D03*
Y313484D03*
X940197Y88484D03*
G54D61*
X1673228Y236614D03*
G54D52*
X59055Y411594D03*
Y236614D03*
X1673228Y411614D03*
G36*
G01X269508Y66522D02*
G02X289549Y66521I10021J6311D01*
G03X287434Y59195I11632J-7326D01*
G01Y53148D01*
G02X271622I-7906J0D01*
G01Y59195D01*
G03X269508Y66522I-13749J2D01*
G37*
G36*
G01X304941Y574397D02*
G02X324982Y574396I10021J6311D01*
G03X322867Y567070I11632J-7326D01*
G01Y561023D01*
G02X307055I-7906J0D01*
G01Y567070D01*
G03X304941Y574397I-13749J2D01*
G37*
G36*
G01X383682Y357862D02*
G02X403723Y357861I10021J6311D01*
G03X401608Y350535I11632J-7326D01*
G01Y344488D01*
G02X385796I-7906J0D01*
G01Y350535D01*
G03X383682Y357862I-13749J2D01*
G37*
G36*
G01X1328564D02*
G02X1348605Y357861I10021J6311D01*
G03X1346490Y350535I11632J-7326D01*
G01Y344488D01*
G02X1330678I-7906J0D01*
G01Y350535D01*
G03X1328564Y357862I-13749J2D01*
G37*
G36*
G01X1407304Y574397D02*
G02X1427345Y574396I10021J6311D01*
G03X1425230Y567070I11632J-7326D01*
G01Y561023D01*
G02X1409418I-7906J0D01*
G01Y567070D01*
G03X1407304Y574397I-13749J2D01*
G37*
G36*
G01X1442736Y66523D02*
G02X1462777Y66522I10021J6311D01*
G03X1460662Y59196I11632J-7326D01*
G01Y53149D01*
G02X1444850I-7906J0D01*
G01Y59196D01*
G03X1442736Y66523I-13749J2D01*
G37*
G36*
G01X41338Y17716D02*
G03X53150I5906J0D01*
G01Y23763D01*
G02X55572Y32155I15747J1D01*
G03X38916I-8328J5246D01*
G02X41338Y23763I-13327J-8392D01*
G01Y17716D01*
G37*
G36*
G01Y330708D02*
G03X53150I5906J0D01*
G01Y336755D01*
G02X55572Y345147I15747J1D01*
G03X38916I-8328J5246D01*
G02X41338Y336755I-13327J-8392D01*
G01Y330708D01*
G37*
G36*
G01X273622Y53148D02*
G03X285434I5906J0D01*
G01Y59195D01*
G02X287856Y67587I15747J1D01*
G03X271200I-8328J5246D01*
G02X273622Y59195I-13327J-8392D01*
G01Y53148D01*
G37*
G36*
G01X309055Y561023D02*
G03X320867I5906J0D01*
G01Y567070D01*
G02X323289Y575462I15747J1D01*
G03X306633I-8328J5246D01*
G02X309055Y567070I-13327J-8392D01*
G01Y561023D01*
G37*
G36*
G01X387796Y344488D02*
G03X399608I5906J0D01*
G01Y350535D01*
G02X402030Y358927I15747J1D01*
G03X385374I-8328J5246D01*
G02X387796Y350535I-13327J-8392D01*
G01Y344488D01*
G37*
G36*
G01X742126Y64961D02*
G03X753938I5906J0D01*
G01Y71008D01*
G02X756360Y79400I15747J1D01*
G03X739704I-8328J5246D01*
G02X742126Y71008I-13327J-8392D01*
G01Y64961D01*
G37*
G36*
G01Y344488D02*
G03X753938I5906J0D01*
G01Y350535D01*
G02X756360Y358927I15747J1D01*
G03X739704I-8328J5246D01*
G02X742126Y350535I-13327J-8392D01*
G01Y344488D01*
G37*
G36*
G01X978346Y64961D02*
G03X990158I5906J0D01*
G01Y71008D01*
G02X992580Y79400I15747J1D01*
G03X975924I-8328J5246D01*
G02X978346Y71008I-13327J-8392D01*
G01Y64961D01*
G37*
G36*
G01Y344488D02*
G03X990158I5906J0D01*
G01Y350535D01*
G02X992580Y358927I15747J1D01*
G03X975924I-8328J5246D01*
G02X978346Y350535I-13327J-8392D01*
G01Y344488D01*
G37*
G36*
G01X1332678D02*
G03X1344490I5906J0D01*
G01Y350535D01*
G02X1346912Y358927I15747J1D01*
G03X1330256I-8328J5246D01*
G02X1332678Y350535I-13327J-8392D01*
G01Y344488D01*
G37*
G36*
G01X1411418Y561023D02*
G03X1423230I5906J0D01*
G01Y567070D01*
G02X1425652Y575462I15747J1D01*
G03X1408996I-8328J5246D01*
G02X1411418Y567070I-13327J-8392D01*
G01Y561023D01*
G37*
G36*
G01X1446850Y53149D02*
G03X1458662I5906J0D01*
G01Y59196D01*
G02X1461084Y67588I15747J1D01*
G03X1444428I-8328J5246D01*
G02X1446850Y59196I-13327J-8392D01*
G01Y53149D01*
G37*
G36*
G01X1679134Y17716D02*
G03X1690946I5906J0D01*
G01Y23763D01*
G02X1693368Y32155I15747J1D01*
G03X1676712I-8328J5246D01*
G02X1679134Y23763I-13327J-8392D01*
G01Y17716D01*
G37*
G36*
G01Y330708D02*
G03X1690946I5906J0D01*
G01Y336755D01*
G02X1693368Y345147I15747J1D01*
G03X1676712I-8328J5246D01*
G02X1679134Y336755I-13327J-8392D01*
G01Y330708D01*
G37*
G36*
G01X1793306Y96457D02*
G03X1805118I5906J0D01*
G01Y102504D01*
G02X1807540Y110896I15747J1D01*
G03X1790884I-8328J5246D01*
G02X1793306Y102504I-13327J-8392D01*
G01Y96457D01*
G37*
G36*
G01Y478346D02*
G03X1805118I5906J0D01*
G01Y484393D01*
G02X1807540Y492785I15747J1D01*
G03X1790884I-8328J5246D01*
G02X1793306Y484393I-13327J-8392D01*
G01Y478346D01*
G37*
G54D11*
X3018Y23930D03*
X10493Y5830D03*
X3018Y43930D03*
Y83930D03*
Y63930D03*
Y103930D03*
Y143930D03*
Y123930D03*
Y163930D03*
Y203930D03*
Y183930D03*
Y223930D03*
Y263930D03*
Y243930D03*
Y283930D03*
Y323930D03*
Y303930D03*
Y343930D03*
Y383930D03*
Y363930D03*
Y403930D03*
Y443930D03*
Y423930D03*
Y463930D03*
Y503930D03*
Y483930D03*
Y523930D03*
Y563930D03*
Y543930D03*
Y583930D03*
X15642Y619715D03*
X3018Y603930D03*
X30709Y3014D03*
X35455Y620194D03*
X75455D03*
X55455D03*
X81406Y3042D03*
X101406D03*
X95455Y620194D03*
X121406Y3042D03*
X134600Y150000D03*
Y134000D03*
X114923Y623982D03*
X124901Y640105D03*
X161406Y3042D03*
X141406D03*
X156785Y101285D03*
X154778Y672779D03*
X181406Y3042D03*
X187600Y106500D03*
X176785Y102000D03*
X194778Y672779D03*
X174778D03*
X201406Y3042D03*
X221406D03*
X211425Y106075D03*
X210925Y115575D03*
X214778Y672779D03*
X229829Y103412D03*
X233329D03*
X237329D03*
X229829Y99503D03*
X233329D03*
X237329D03*
X229953Y95780D03*
X233453D03*
X237453D03*
X229891Y92305D03*
X233391D03*
X237391D03*
X254778Y672779D03*
X234778D03*
X274778D03*
X317000Y58000D03*
X314766Y39211D03*
X317766D03*
X317000Y74475D03*
Y64500D03*
X311956Y651522D03*
X294778Y672779D03*
X323766Y39211D03*
X320766D03*
X321500Y74475D03*
Y66500D03*
X325100Y64000D03*
X332500Y63300D03*
X330500Y74476D03*
X324000Y77000D03*
X321000Y63000D03*
X326000Y74476D03*
X345412Y435017D03*
Y455017D03*
Y475017D03*
Y495017D03*
Y515017D03*
Y535017D03*
Y555017D03*
Y575017D03*
Y595017D03*
X342119Y613510D03*
X331285Y620008D03*
X369192Y38417D03*
X372192D03*
X378192D03*
X375192D03*
X362127Y406608D03*
X350024Y418335D03*
X396216Y46875D03*
X408100Y180100D03*
Y224500D03*
X399680Y402510D03*
X379680D03*
X428277Y167056D03*
X438100Y170000D03*
X430608Y211389D03*
X438100Y214500D03*
X419680Y402510D03*
X441938Y87700D03*
Y132100D03*
Y176500D03*
Y220900D03*
Y265300D03*
Y309700D03*
X459680Y402510D03*
X439680D03*
X479680D03*
X517409Y322000D03*
X506309Y329000D03*
Y322000D03*
X517410Y329000D03*
X499680Y402510D03*
X519680D03*
X551430Y132400D03*
X561155Y160784D03*
X551430Y265600D03*
X539680Y402510D03*
X559680D03*
X563007Y118477D03*
Y114123D03*
X562830Y133300D03*
Y136800D03*
Y140300D03*
Y143800D03*
X574230Y132400D03*
X564305Y160784D03*
X563007Y251677D03*
X576467Y265600D03*
X563007Y247323D03*
X562830Y270000D03*
Y266500D03*
X590298Y282890D03*
X562830Y277000D03*
X571325Y292757D03*
X590298Y276984D03*
X562830Y273500D03*
X571542Y289065D03*
X565091Y302592D03*
X570443Y302702D03*
X579680Y402510D03*
X620600Y239161D03*
X605800Y256500D03*
X609637Y254523D03*
X605700Y259500D03*
X616184Y267000D03*
X604684D03*
X612684Y297000D03*
X616684Y294500D03*
X602928Y293969D03*
X606084Y293100D03*
X600875Y295937D03*
X616184Y276000D03*
X604684D03*
Y285000D03*
X616184D03*
X590684Y313800D03*
Y310800D03*
X601675Y305575D03*
X616684Y307975D03*
X622184Y308000D03*
X608259Y305000D03*
X618500Y333500D03*
X619680Y402510D03*
X599680D03*
X639010Y236377D03*
X640684Y264500D03*
Y269000D03*
X645900Y242200D03*
X644502Y246839D03*
X649200Y254500D03*
X650100Y251500D03*
X623684Y281000D03*
X637684Y280575D03*
X629018Y277500D03*
X625684Y273499D03*
X630308Y284500D03*
X649059Y314000D03*
X632186Y338917D03*
X623500Y379000D03*
X639680Y402510D03*
X676638Y230894D03*
X681684Y230820D03*
X657259Y263000D03*
X674800Y269600D03*
X660684Y262500D03*
X654100Y263000D03*
X651100Y266000D03*
X679184Y278980D03*
X673684Y280950D03*
X676684D03*
X670184Y288500D03*
X662184Y280500D03*
Y288500D03*
Y284500D03*
X659000Y284000D03*
X679184Y273190D03*
X676184Y274000D03*
X657500Y330075D03*
X662075Y320000D03*
X675100Y304500D03*
X662125Y308500D03*
X671000Y315760D03*
X668000Y311500D03*
X663500D03*
X657500Y326925D03*
X662100Y304500D03*
X658925Y320000D03*
X659680Y402510D03*
X679680D03*
X702223Y197419D03*
X704240Y185000D03*
X689684Y230762D03*
X683592Y259908D03*
X688945Y259761D03*
X695259Y248020D03*
X706984Y261100D03*
X710084D03*
X691794Y261073D03*
X692109Y248020D03*
X686784Y268100D03*
X695584D03*
X698433Y247119D03*
X685884Y297000D03*
X702984Y283500D03*
X706684D03*
X702984Y272400D03*
X706684D03*
X686784Y278000D03*
X695584D03*
X686784Y287900D03*
X695684D03*
X710900Y324100D03*
X691759Y309000D03*
X699680Y402510D03*
X712000Y215500D03*
X717384Y273400D03*
X719484Y278980D03*
X725000Y292500D03*
X722925Y299500D03*
X719433Y328087D03*
X734500Y307425D03*
X719500Y315500D03*
X734500Y310575D03*
X717401Y329996D03*
X739680Y402510D03*
X719680D03*
X770700Y206900D03*
X759680Y402510D03*
X776000Y206600D03*
X779680Y402510D03*
X799680D03*
X819680D03*
X862600Y29500D03*
X839680Y402510D03*
X859680D03*
X867100Y28000D03*
X872533Y29432D03*
X867100Y31500D03*
X887500Y355680D03*
X885100Y361500D03*
X885265Y381000D03*
X878175Y374100D03*
Y364709D03*
X879680Y402510D03*
X919680D03*
X899680D03*
X894500Y396500D03*
X954200Y200200D03*
X954600Y207200D03*
X939680Y402510D03*
X978600Y310955D03*
X959680Y402510D03*
X979680D03*
X999680D03*
X1034537Y201437D03*
X1024600Y185000D03*
X1027675Y215000D03*
X1024525D03*
X1034360Y254000D03*
X1044900Y278600D03*
X1042800Y273020D03*
X1017300Y322500D03*
X1026270Y303729D03*
X1023492Y346593D03*
X1021414Y355979D03*
X1017300Y385600D03*
X1039680Y402510D03*
X1019680D03*
X1047163Y197437D03*
X1066600Y264100D03*
X1074430Y256461D03*
X1059300Y268500D03*
X1055600D03*
X1070525Y243000D03*
X1066700Y274000D03*
Y283900D03*
X1052200Y290900D03*
X1055300D03*
X1070490Y290927D03*
X1055600Y279600D03*
X1059300D03*
X1073339Y292239D03*
X1062600Y305000D03*
X1070175Y303980D03*
X1067025D03*
X1072600Y324000D03*
X1064600D03*
X1065800Y339500D03*
X1063300D03*
X1073800D03*
X1071300D03*
X1059680Y402510D03*
X1092100Y263500D03*
X1100100Y243500D03*
X1100500Y263500D03*
X1100100Y247500D03*
X1075500Y264100D03*
X1085600Y271050D03*
X1101500Y271500D03*
X1083100Y273020D03*
X1088079Y274980D03*
X1087100Y282500D03*
X1101600Y289500D03*
X1080600Y294000D03*
X1075500Y274000D03*
Y283900D03*
X1102600Y296000D03*
X1083100Y278810D03*
X1086100Y278000D03*
X1080600Y324000D03*
X1081800Y339500D03*
X1079300D03*
X1086800D03*
X1089300D03*
X1094500Y355600D03*
Y360500D03*
X1079680Y402510D03*
X1099680D03*
X1129800Y265400D03*
X1131976Y267500D03*
X1108100Y289000D03*
X1121600Y287500D03*
Y283000D03*
X1105025Y289000D03*
X1111100Y291500D03*
Y285000D03*
X1121100Y296000D03*
X1124600Y271425D03*
X1132113Y274500D03*
X1112000Y296000D03*
X1111100Y300500D03*
X1118000Y303500D03*
X1123100Y322500D03*
Y319500D03*
X1130100Y305174D03*
X1130510Y307720D03*
X1123400Y356300D03*
X1132000Y367000D03*
X1119680Y402510D03*
X1145600Y257500D03*
X1149600Y255000D03*
X1160990Y252134D03*
X1146100Y267000D03*
X1157600D03*
X1156200Y258900D03*
X1145600Y244025D03*
X1140100Y244000D03*
X1154025Y247000D03*
X1163266Y255311D03*
X1156584Y292488D03*
X1156509Y295396D03*
X1157600Y276000D03*
X1146100D03*
Y285000D03*
X1157600D03*
X1136000Y278953D03*
X1141600Y305161D03*
X1154600Y321050D03*
X1143100Y322500D03*
Y320000D03*
X1157800Y312050D03*
X1157138Y303000D03*
X1141600Y312839D03*
X1141500Y347500D03*
X1138500D03*
X1162425Y340500D03*
X1147000Y342500D03*
X1166000Y352500D03*
X1163000D03*
X1153500Y342500D03*
X1159680Y402510D03*
X1139680D03*
X1187700Y132400D03*
X1197425Y160284D03*
X1187700Y265600D03*
X1171986Y269110D03*
X1196500Y293284D03*
X1171986Y275016D03*
X1176000Y350000D03*
X1167800Y355000D03*
X1168200Y349700D03*
X1165575Y340500D03*
X1171700Y349900D03*
X1178900Y359620D03*
X1179500Y350000D03*
Y355000D03*
X1179680Y402510D03*
X1199277Y118477D03*
Y114123D03*
X1210500Y132400D03*
X1199100Y140300D03*
Y133300D03*
Y143800D03*
Y136800D03*
X1200575Y160284D03*
X1199277Y247323D03*
X1210500Y265600D03*
X1199277Y251677D03*
X1199100Y270000D03*
Y266500D03*
X1201500Y293284D03*
X1199100Y277000D03*
Y273500D03*
X1201037Y318912D03*
X1197127Y314264D03*
X1199680Y402510D03*
X1219680D03*
X1244874Y330000D03*
X1255975D03*
Y337000D03*
X1239680Y402510D03*
X1259680D03*
X1279680D03*
X1313366Y38482D03*
X1307366D03*
X1310366D03*
X1299680Y402510D03*
X1316366Y38482D03*
X1320346Y67900D03*
Y112300D03*
X1334140Y146642D03*
X1324100Y150500D03*
X1320346Y156700D03*
X1324100Y194900D03*
X1332671Y190644D03*
X1320346Y201100D03*
Y245500D03*
Y289900D03*
X1339680Y402510D03*
X1319680D03*
X1355310Y38893D03*
X1352310D03*
X1349310D03*
X1358310D03*
X1355100Y160000D03*
X1355000Y204400D03*
X1359620Y402940D03*
X1386882Y434539D03*
Y454539D03*
Y474539D03*
Y494539D03*
Y514539D03*
Y534539D03*
Y554539D03*
Y574539D03*
Y594539D03*
X1389643Y612723D03*
X1403035Y620181D03*
X1422310Y40481D03*
X1419310D03*
X1416310D03*
X1425310D03*
X1420335Y635388D03*
Y655388D03*
X1428754Y670547D03*
X1445829Y672778D03*
X1465829D03*
X1498180Y63500D03*
X1494728Y83500D03*
X1490000Y80500D03*
X1499228Y74500D03*
X1490000Y84000D03*
X1494728Y66500D03*
X1490228D03*
X1491918Y107773D03*
Y110773D03*
Y113773D03*
Y104773D03*
X1488918D03*
Y113773D03*
Y110773D03*
Y107773D03*
X1485918Y104773D03*
Y113773D03*
Y110773D03*
Y107773D03*
X1482918Y104773D03*
Y113773D03*
Y110773D03*
Y107773D03*
X1485829Y672778D03*
X1508460Y3003D03*
X1505100Y64500D03*
X1503728Y74477D03*
X1527100Y108500D03*
Y98925D03*
X1524600Y111500D03*
X1505829Y672778D03*
X1525829D03*
X1548460Y3003D03*
X1528460D03*
X1531600Y96941D03*
X1551000Y96500D03*
X1545829Y672778D03*
X1588460Y3003D03*
X1568460D03*
X1567500Y67000D03*
X1565829Y672778D03*
X1585829D03*
X1608460Y3003D03*
X1609100Y85500D03*
Y82000D03*
X1606100Y85500D03*
Y82000D03*
X1609100Y69500D03*
Y66000D03*
Y62500D03*
X1606100Y69500D03*
Y66000D03*
Y62500D03*
X1618800Y76700D03*
X1615800Y82700D03*
Y79700D03*
Y76700D03*
X1602100Y85500D03*
Y82000D03*
Y69500D03*
Y66000D03*
Y62500D03*
X1594930Y115000D03*
X1614100Y110000D03*
Y115000D03*
X1609100Y89000D03*
X1606100D03*
X1602100D03*
X1597100Y145000D03*
Y126000D03*
X1614100Y125000D03*
Y120000D03*
Y130000D03*
X1618100Y148925D03*
X1613527Y627220D03*
X1607226Y650448D03*
X1602599Y667628D03*
X1648460Y3003D03*
X1628460D03*
X1618800Y79700D03*
Y82700D03*
X1647800Y83200D03*
Y77200D03*
Y80200D03*
X1622295Y114940D03*
X1629870Y104240D03*
X1625370Y103940D03*
X1642037Y104134D03*
X1643537Y101434D03*
X1640037D03*
X1638537Y104134D03*
X1645537D03*
X1647037Y101434D03*
X1632336Y109117D03*
X1631323Y115140D03*
X1624500Y142500D03*
Y146000D03*
X1622295Y118940D03*
X1647837Y121812D03*
X1638707Y132954D03*
X1644917Y124581D03*
X1641932Y122969D03*
X1635000Y152925D03*
X1623100Y172500D03*
Y178000D03*
X1650117Y180000D03*
X1636600Y173500D03*
X1622100Y155931D03*
X1626000Y163500D03*
Y167500D03*
X1626925Y156000D03*
X1629000Y175000D03*
X1631585Y188777D03*
X1624000Y189000D03*
X1642000Y184500D03*
X1645000D03*
X1628658Y620261D03*
X1648675Y620226D03*
X1657050Y102380D03*
X1662000Y106000D03*
X1660250Y113860D03*
X1657050Y116760D03*
Y113860D03*
X1660250Y116760D03*
X1669800Y120400D03*
X1675800D03*
X1651037Y99734D03*
X1658500Y138000D03*
X1649197Y132915D03*
X1650990Y122034D03*
X1667000Y138000D03*
X1672800Y120400D03*
X1656657Y127365D03*
X1651325Y125076D03*
X1649500Y173398D03*
X1676350Y160251D03*
X1672050Y181550D03*
X1668075Y189500D03*
X1679176Y194760D03*
X1657500Y191500D03*
X1664000Y202500D03*
X1661500Y199000D03*
X1667600Y198500D03*
X1658000Y179500D03*
X1654000Y192500D03*
X1660000Y193500D03*
X1652600Y212000D03*
X1668675Y620226D03*
X1708460Y3003D03*
X1692000Y76570D03*
X1695500Y76500D03*
X1706100Y92000D03*
X1701350Y114250D03*
X1696600Y119000D03*
X1682500Y121825D03*
X1697976Y148000D03*
X1690100Y127375D03*
X1685100Y127500D03*
X1702525Y129500D03*
X1685976Y148000D03*
X1692600Y135975D03*
X1688100Y145560D03*
X1705100Y140500D03*
X1707100Y142500D03*
X1685000Y133000D03*
X1702600Y171500D03*
X1697976Y164500D03*
Y159000D03*
Y175500D03*
Y170000D03*
Y153500D03*
X1680000Y156500D03*
X1685976Y164500D03*
Y159000D03*
Y153500D03*
Y175500D03*
Y170000D03*
X1701100Y178500D03*
X1688100Y173060D03*
Y162060D03*
X1709600Y158000D03*
X1701000Y159000D03*
Y164500D03*
X1685975Y186500D03*
X1701100Y182000D03*
X1688100Y184220D03*
X1697975Y181000D03*
X1704600Y201500D03*
X1685976Y181000D03*
X1702075Y205500D03*
X1688692Y620191D03*
X1708692D03*
X1729255Y25347D03*
Y45347D03*
X1718675Y88000D03*
X1732786Y58461D03*
X1719075Y107016D03*
Y112000D03*
X1718675Y99000D03*
Y93500D03*
X1713524Y109500D03*
Y114500D03*
X1721685Y95940D03*
X1727200Y104500D03*
X1738000Y124500D03*
X1721000Y142525D03*
X1714100Y144925D03*
X1713525Y134500D03*
Y129500D03*
X1713524Y119500D03*
X1729411Y143661D03*
X1727100Y164280D03*
X1715525Y168500D03*
Y153000D03*
X1722063Y156962D03*
X1726099Y153000D03*
X1720524Y175000D03*
X1717600Y158000D03*
X1720100Y179500D03*
X1729411Y159161D03*
X1733500Y173760D03*
X1712000Y153000D03*
X1728475Y175000D03*
X1731925Y199000D03*
X1714175Y187000D03*
X1738740Y191500D03*
X1729000Y183500D03*
X1724824Y205276D03*
X1711025Y187000D03*
X1721500Y205000D03*
X1721600Y194760D03*
Y198500D03*
X1729275Y562751D03*
Y542751D03*
Y582751D03*
Y602751D03*
X1753635Y69037D03*
X1767525Y114016D03*
X1759600Y114500D03*
X1767425Y107000D03*
X1761600Y124524D03*
X1764000Y142525D03*
X1767425Y137000D03*
X1768500Y142525D03*
X1770575Y137000D03*
X1764100Y119500D03*
X1764000Y158025D03*
X1759925Y178900D03*
X1768500Y158025D03*
X1763925Y170984D03*
Y155484D03*
X1763075Y178900D03*
X1767075Y155484D03*
X1769476Y168500D03*
X1766925Y181500D03*
X1769425Y203000D03*
X1754925D03*
X1754260Y187260D03*
X1768000D03*
X1746000Y191240D03*
X1750563Y198000D03*
X1747925Y204000D03*
X1751600Y238000D03*
Y235500D03*
X1740600D03*
Y238000D03*
X1751600Y233000D03*
X1740600D03*
X1751600Y258000D03*
Y255500D03*
X1740600Y258000D03*
Y255500D03*
Y248000D03*
Y250500D03*
Y253000D03*
X1751600D03*
Y250500D03*
Y248000D03*
X1766432Y250301D03*
Y247301D03*
X1766447Y239798D03*
Y242798D03*
X1751600Y240500D03*
X1740600D03*
X1769300Y329400D03*
Y340600D03*
X1769692Y334649D03*
X1767700Y346200D03*
X1767600Y350000D03*
X1755454Y515746D03*
X1793635Y69037D03*
X1773635D03*
X1772975Y109500D03*
Y104500D03*
X1773076Y117500D03*
X1773000Y142525D03*
X1773500Y129500D03*
X1772975Y124500D03*
X1773000Y158000D03*
X1772600Y177300D03*
X1772500Y174000D03*
X1800100Y187500D03*
X1770075Y181500D03*
X1778000Y189500D03*
X1789600Y247000D03*
X1783932Y250357D03*
Y247357D03*
X1775432Y250357D03*
Y247357D03*
X1783947Y239798D03*
Y242798D03*
X1775447Y239798D03*
Y242798D03*
X1789600Y243500D03*
X1795600Y308000D03*
X1777375Y356300D03*
X1777383Y352305D03*
X1784035Y389535D03*
X1781535D03*
X1784035Y386935D03*
X1781535D03*
X1778838Y389508D03*
Y386908D03*
X1781535Y402935D03*
X1784035D03*
X1778838Y402908D03*
X1781535Y405535D03*
X1784035D03*
X1778838Y405508D03*
X1775454Y515746D03*
X1813635Y69037D03*
X1817500Y188000D03*
X1809600Y195000D03*
X1811500Y186000D03*
X1815454Y515746D03*
X1853635Y69037D03*
X1833635D03*
X1842164Y419238D03*
X1847164D03*
X1837164D03*
X1852164D03*
X1842164Y432338D03*
X1847164Y430568D03*
X1852164Y435538D03*
X1837164Y428238D03*
X1835454Y515746D03*
X1855509Y515697D03*
X1871008Y117112D03*
X1871009Y93913D03*
X1871008Y137112D03*
Y177112D03*
Y157112D03*
Y197112D03*
Y237112D03*
Y217112D03*
Y257112D03*
Y297112D03*
Y277112D03*
Y317112D03*
Y357112D03*
Y337112D03*
Y377112D03*
Y417112D03*
Y397112D03*
Y437112D03*
Y477112D03*
Y457112D03*
Y497112D03*
G54D43*
X1673228Y222834D03*
X1663385Y226771D03*
X1659448Y236614D03*
X1663385Y246457D03*
X1673228Y250394D03*
X1687008Y236614D03*
X1683071Y226771D03*
Y246457D03*
G54D19*
X166785Y200472D03*
Y280472D03*
Y360472D03*
Y440472D03*
Y520472D03*
X243785Y200472D03*
Y280472D03*
Y360472D03*
Y440472D03*
Y520472D03*
X1488500Y200472D03*
Y280472D03*
Y360472D03*
Y440472D03*
Y520472D03*
X1565500Y200472D03*
Y280472D03*
Y360472D03*
Y440472D03*
Y520472D03*
G54D49*
X1848957Y324213D03*
X1843957Y329213D03*
X1848957Y314213D03*
X1843957Y319213D03*
X1853957Y329213D03*
Y319213D03*
X1848957Y334213D03*
Y344213D03*
X1843957Y339213D03*
Y349213D03*
X1853957D03*
Y339213D03*
X1858957Y344213D03*
Y334213D03*
G54D15*
X45275Y236614D03*
Y411594D03*
X72835Y236614D03*
X68898Y226771D03*
X59055Y222834D03*
X49212Y226771D03*
X68898Y246457D03*
X49212D03*
X59055Y250394D03*
X68898Y421437D03*
X72835Y411594D03*
X68898Y401751D03*
X59055Y397814D03*
X49212Y401751D03*
Y421437D03*
X59055Y425374D03*
X1673228Y397834D03*
X1663385Y401771D03*
X1659448Y411614D03*
X1663385Y421457D03*
X1673228Y425394D03*
X1683071Y421457D03*
X1687008Y411614D03*
X1683071Y401771D03*
G54D42*
X1642915Y111950D03*
X1639372Y114450D03*
X1646458Y111950D03*
X1642915Y114450D03*
X1639372Y111950D03*
X1646458Y114450D03*
X1650002Y111950D03*
Y114450D03*
G54D29*
X454738Y56000D03*
X451738D03*
X448738D03*
X445738D03*
X442738D03*
X454738Y68000D03*
Y65000D03*
Y62000D03*
Y59000D03*
X451738D03*
Y62000D03*
Y65000D03*
Y68000D03*
X448738Y59000D03*
Y62000D03*
Y65000D03*
Y68000D03*
X445738Y59000D03*
Y62000D03*
Y65000D03*
Y68000D03*
X442738Y59000D03*
Y62000D03*
Y65000D03*
Y68000D03*
X454738Y112400D03*
Y109400D03*
Y106400D03*
Y103400D03*
X451738D03*
Y106400D03*
Y109400D03*
Y112400D03*
X448738Y103400D03*
Y106400D03*
Y109400D03*
Y112400D03*
X445738Y103400D03*
Y106400D03*
Y109400D03*
Y112400D03*
X442738Y103400D03*
Y106400D03*
Y109400D03*
Y112400D03*
X454738Y100400D03*
X451738D03*
X448738D03*
X445738D03*
X442738D03*
X454738Y147800D03*
X451738D03*
X448738D03*
X445738D03*
X442738D03*
X454738Y144800D03*
X451738D03*
X448738D03*
X445738D03*
X442738D03*
X454738Y156800D03*
Y153800D03*
Y150800D03*
X451738D03*
Y153800D03*
Y156800D03*
X448738Y150800D03*
Y153800D03*
Y156800D03*
X445738Y150800D03*
Y153800D03*
Y156800D03*
X442738Y150800D03*
Y153800D03*
Y156800D03*
X454738Y201200D03*
Y198200D03*
Y195200D03*
Y192200D03*
X451738D03*
Y195200D03*
Y198200D03*
Y201200D03*
X448738Y192200D03*
Y195200D03*
Y198200D03*
Y201200D03*
X445738Y192200D03*
Y195200D03*
Y198200D03*
Y201200D03*
X442738Y192200D03*
Y195200D03*
Y198200D03*
Y201200D03*
X454738Y189200D03*
X451738D03*
X448738D03*
X445738D03*
X442738D03*
X454738Y239600D03*
Y236600D03*
X451738D03*
Y239600D03*
X448738Y236600D03*
Y239600D03*
X445738Y236600D03*
Y239600D03*
X442738Y236600D03*
Y239600D03*
X454738Y233600D03*
X451738D03*
X448738D03*
X445738D03*
X442738D03*
X454738Y245600D03*
Y242600D03*
X451738D03*
Y245600D03*
X448738Y242600D03*
Y245600D03*
X445738Y242600D03*
Y245600D03*
X442738Y242600D03*
Y245600D03*
X448738Y278000D03*
X451738D03*
X454738D03*
X448738Y290000D03*
Y287000D03*
Y284000D03*
Y281000D03*
X451738Y290000D03*
Y287000D03*
Y284000D03*
Y281000D03*
X454738D03*
Y284000D03*
Y287000D03*
Y290000D03*
X445738D03*
Y287000D03*
Y284000D03*
Y281000D03*
Y278000D03*
X442738Y290000D03*
Y287000D03*
Y284000D03*
Y281000D03*
Y278000D03*
X468946Y338216D03*
X465946D03*
X468946Y341216D03*
X465946D03*
X458946Y338216D03*
X455946D03*
X458946Y341216D03*
X455946D03*
Y357216D03*
X458946D03*
X468946Y357016D03*
X465946D03*
X471946Y338216D03*
Y341216D03*
X481446Y338216D03*
X478446D03*
X481446Y341216D03*
X478446D03*
X484446Y338216D03*
Y341216D03*
X471946Y357016D03*
X528084Y77900D03*
Y74900D03*
Y71900D03*
X525084Y77900D03*
Y74900D03*
Y71900D03*
X522084Y77900D03*
Y74900D03*
Y71900D03*
X525084Y116300D03*
X522084D03*
X528084D03*
X525084Y122300D03*
X522084D03*
X525084Y119300D03*
X522084D03*
X528084Y122300D03*
Y119300D03*
X525084Y166700D03*
X522084D03*
X525084Y160700D03*
Y163700D03*
X522084D03*
Y160700D03*
Y205100D03*
Y208100D03*
X525084D03*
Y205100D03*
X522084Y211100D03*
X525084D03*
X522084Y249500D03*
Y252500D03*
X525084D03*
Y249500D03*
X522084Y255500D03*
X525084D03*
X528084Y252500D03*
Y249500D03*
Y255500D03*
Y299900D03*
X525084D03*
X522084D03*
X528084Y296900D03*
X525084D03*
X522084D03*
X528084Y293900D03*
X525084D03*
X522084D03*
X531084Y77900D03*
Y74900D03*
Y71900D03*
Y299900D03*
Y296900D03*
Y293900D03*
X586184Y117800D03*
X583184D03*
X580184D03*
X586184Y114800D03*
X583184D03*
X580184D03*
X586184Y111800D03*
X583184D03*
X580184D03*
X586184Y108800D03*
X583184D03*
X580184D03*
X586184Y105800D03*
X583184D03*
X580184D03*
Y126800D03*
X583184D03*
X586184D03*
Y123800D03*
X583184D03*
X580184D03*
X586184Y120800D03*
X583184D03*
X580184D03*
X583184Y239000D03*
X580184D03*
X583184Y242000D03*
X580184D03*
X583184Y254000D03*
Y251000D03*
Y248000D03*
Y245000D03*
X580184D03*
Y248000D03*
Y251000D03*
Y254000D03*
X583184Y260000D03*
Y257000D03*
X580184D03*
Y260000D03*
X595276Y239710D03*
X592476D03*
X620466Y246839D03*
X658600Y237700D03*
X655600D03*
X664484Y212500D03*
X666984D03*
X672484D03*
X674984D03*
X679484D03*
X681984D03*
X685484D03*
X687984D03*
X1240200Y77900D03*
Y74900D03*
Y71900D03*
Y68900D03*
Y65900D03*
X1237200D03*
Y68900D03*
Y71900D03*
Y74900D03*
Y77900D03*
X1234200Y65900D03*
Y68900D03*
Y71900D03*
Y74900D03*
Y77900D03*
X1231200Y65900D03*
Y68900D03*
Y71900D03*
Y74900D03*
Y77900D03*
X1234200Y116300D03*
Y113300D03*
Y110300D03*
X1237200Y116300D03*
Y113300D03*
Y110300D03*
X1240200D03*
Y113300D03*
Y116300D03*
X1234200Y122300D03*
Y119300D03*
X1237200Y122300D03*
Y119300D03*
X1240200D03*
Y122300D03*
X1237200Y166700D03*
Y163700D03*
Y160700D03*
Y157700D03*
Y154700D03*
X1240200D03*
Y157700D03*
Y160700D03*
Y163700D03*
Y166700D03*
X1237200Y208100D03*
X1240200D03*
X1237200Y211100D03*
X1240200D03*
X1234200Y252500D03*
X1237200D03*
X1234200Y255500D03*
X1237200D03*
X1240200Y252500D03*
Y255500D03*
Y299900D03*
Y296900D03*
X1237200D03*
Y299900D03*
X1234200Y296900D03*
Y299900D03*
X1231200Y296900D03*
Y299900D03*
G54D44*
X1728600Y387500D03*
X1731100D03*
X1733600D03*
X1762454Y320347D03*
X1742109Y345235D03*
Y342435D03*
X1747416Y348293D03*
X1747909Y345335D03*
Y342535D03*
X1744909Y345335D03*
Y342535D03*
X1742109Y339635D03*
Y336835D03*
Y334035D03*
X1747909Y339735D03*
Y336935D03*
Y334135D03*
X1744909Y339735D03*
Y336935D03*
Y334135D03*
X1767151Y333311D03*
X1777532Y328322D03*
X1777459Y332322D03*
X1777383Y348288D03*
G54D34*
X802087Y200984D03*
X792087D03*
X822087D03*
X812087D03*
X920197D03*
X910197D03*
X940197D03*
X930197D03*
G54D37*
X825900Y362200D03*
Y372200D03*
X866400Y362200D03*
Y382200D03*
X906900Y362200D03*
Y372200D03*
G54D18*
X137303Y601693D03*
Y609567D03*
Y617441D03*
Y625315D03*
Y633189D03*
Y641063D03*
Y648937D03*
Y656811D03*
Y664685D03*
X145177Y601693D03*
Y609567D03*
Y617441D03*
Y625315D03*
Y633189D03*
Y641063D03*
Y648937D03*
Y656811D03*
Y664685D03*
X1576280Y601693D03*
X1568406D03*
X1576280Y609567D03*
Y617441D03*
Y625315D03*
Y633189D03*
X1568406Y609567D03*
Y617441D03*
Y625315D03*
Y633189D03*
X1576280Y641063D03*
Y648937D03*
Y656811D03*
X1568406Y641063D03*
Y648937D03*
Y656811D03*
X1576280Y664685D03*
X1568406D03*
G54D31*
X681498Y575042D03*
Y565042D03*
X681604Y593187D03*
Y603187D03*
X997833Y575042D03*
Y565042D03*
Y593187D03*
Y603187D03*
G54D45*
X1848583Y99212D03*
X1848582Y481693D03*
G54D21*
X163878Y601693D03*
X156004D03*
X163878Y609567D03*
Y617441D03*
Y625315D03*
Y633189D03*
X156004Y609567D03*
Y617441D03*
Y625315D03*
Y633189D03*
X163878Y641063D03*
Y648937D03*
Y656811D03*
X156004Y641063D03*
Y648937D03*
Y656811D03*
X163878Y664685D03*
X156004D03*
X192126Y656811D03*
Y648937D03*
Y664685D03*
X215748Y656811D03*
Y648937D03*
X223622Y656811D03*
Y648937D03*
X200000Y656811D03*
Y648937D03*
X215748Y664685D03*
X223622D03*
X200000D03*
X250866Y20827D03*
X255906Y648937D03*
X248032D03*
X255906Y656811D03*
X248032D03*
X255906Y664685D03*
X248032D03*
X279646Y23012D03*
Y13012D03*
X284646Y18012D03*
X274646D03*
X284646Y8012D03*
X274646D03*
X260866Y20827D03*
X279528Y648937D03*
X271654D03*
X279528Y656811D03*
X271654D03*
X279528Y664685D03*
X271654D03*
X289646Y23012D03*
Y13012D03*
X303150Y648937D03*
X295276D03*
X303150Y656811D03*
X295276D03*
X303150Y664685D03*
X295276D03*
X1437008Y648937D03*
X1429134D03*
X1437008Y656811D03*
X1429134D03*
X1437008Y664685D03*
X1429134D03*
X1465197Y18012D03*
Y8012D03*
X1451417Y20827D03*
X1441417D03*
X1460630Y648937D03*
X1452756D03*
X1460630Y656811D03*
X1452756D03*
X1460630Y664685D03*
X1452756D03*
X1480197Y23012D03*
X1470197D03*
X1480197Y13012D03*
X1470197D03*
X1475197Y18012D03*
Y8012D03*
X1484252Y648937D03*
X1476378D03*
X1484252Y656811D03*
X1476378D03*
X1484252Y664685D03*
X1476378D03*
X1508661Y656811D03*
Y648937D03*
X1516535Y656811D03*
Y648937D03*
X1508661Y664685D03*
X1516535D03*
X1532283Y656811D03*
Y648937D03*
X1540157Y656811D03*
Y648937D03*
X1532283Y664685D03*
X1540157D03*
X1587107Y601693D03*
Y609567D03*
Y617441D03*
Y625315D03*
Y633189D03*
Y641063D03*
Y648937D03*
Y656811D03*
Y664685D03*
X1594981Y601693D03*
Y609567D03*
Y617441D03*
Y625315D03*
Y633189D03*
Y641063D03*
Y648937D03*
Y656811D03*
Y664685D03*
G54D47*
X1846142Y230433D03*
Y240433D03*
X1856772D03*
Y230433D03*
X1846142Y250433D03*
Y260433D03*
Y270433D03*
X1856772D03*
Y260433D03*
Y250433D03*
X1846142Y280433D03*
Y290433D03*
Y300433D03*
X1856772D03*
Y290433D03*
Y280433D03*
X1858957Y324213D03*
Y314213D03*
G54D38*
X825900Y382200D03*
X906900D03*
G54D41*
X1011017Y598187D03*
G54D40*
Y570042D03*
G54D25*
X207874Y639095D03*
X1524409D03*
G54D14*
X47244Y17716D03*
Y330708D03*
X748032Y64961D03*
Y344488D03*
X984252Y64961D03*
Y344488D03*
X1685040Y17716D03*
Y330708D03*
X1799212Y96457D03*
Y478346D03*
G54D28*
X287402Y628465D03*
X263780Y659961D03*
X1468504Y628465D03*
X1444882Y659961D03*
G54D10*
X19685Y-774040D03*
Y766166D03*
X240866Y15512D03*
X300866Y10197D03*
X566575Y463701D03*
D03*
D03*
X1431417Y15512D03*
X1491417Y10197D03*
X1854331Y-774040D03*
Y766166D03*
G54D48*
X1851457Y220433D03*
X1856772Y360433D03*
G54D23*
X231600Y81000D03*
X1212478Y300181D03*
X1529100Y78500D03*
G54D35*
X822087Y88484D03*
Y313484D03*
X940197Y88484D03*
Y313484D03*
G54D22*
X192126Y633189D03*
Y625315D03*
Y617441D03*
X200000Y633189D03*
Y625315D03*
Y617441D03*
X215748Y633189D03*
Y625315D03*
Y617441D03*
X223622Y633189D03*
Y625315D03*
Y617441D03*
X255906D03*
X248032D03*
X255906Y625315D03*
Y633189D03*
X248032D03*
Y625315D03*
X279528Y617441D03*
X271654D03*
X279528Y625315D03*
Y633189D03*
X271654D03*
Y625315D03*
X295276Y617441D03*
Y625315D03*
Y633189D03*
X303150D03*
Y625315D03*
Y617441D03*
X1437008D03*
X1429134D03*
X1437008Y625315D03*
Y633189D03*
X1429134D03*
Y625315D03*
X1460630Y617441D03*
X1452756D03*
X1460630Y625315D03*
Y633189D03*
X1452756D03*
Y625315D03*
X1476378Y617441D03*
Y625315D03*
Y633189D03*
X1484252D03*
Y625315D03*
Y617441D03*
X1508661Y633189D03*
Y625315D03*
Y617441D03*
X1516535Y633189D03*
Y625315D03*
Y617441D03*
X1532283Y633189D03*
Y625315D03*
Y617441D03*
X1540157Y633189D03*
Y625315D03*
Y617441D03*
G54D26*
X250866Y10197D03*
X260866D03*
X1451417D03*
X1441417D03*
G54D24*
X225829Y103412D03*
Y99503D03*
X225953Y95780D03*
X225891Y92305D03*
X622288Y235790D03*
X624788D03*
X1173500Y298500D03*
X1176200Y316500D03*
X1173200D03*
X1733600Y397500D03*
X1731100D03*
X1728600D03*
G54D17*
X137355Y120500D03*
X205061Y85500D03*
Y79000D03*
Y75000D03*
Y71500D03*
Y67500D03*
Y89500D03*
Y93000D03*
Y97000D03*
X200600Y109059D03*
X205100Y123000D03*
X325500Y15000D03*
Y18000D03*
Y21000D03*
X340500D03*
Y18000D03*
Y15000D03*
X337500Y21000D03*
Y18000D03*
Y15000D03*
X334500Y21000D03*
Y18000D03*
Y15000D03*
X331500Y21000D03*
Y18000D03*
Y15000D03*
X328500Y21000D03*
Y18000D03*
Y15000D03*
X498923Y37456D03*
X495923D03*
X492923D03*
X489923D03*
X501923D03*
X504923D03*
X510923D03*
X507923D03*
X528084Y68900D03*
Y65900D03*
X525084Y68900D03*
Y65900D03*
X522084Y68900D03*
Y65900D03*
X525084Y113300D03*
Y110300D03*
X522084Y113300D03*
Y110300D03*
X528084Y113300D03*
Y110300D03*
X525084Y157700D03*
Y154700D03*
X522084Y157700D03*
Y154700D03*
Y199100D03*
Y202100D03*
X525084Y199100D03*
Y202100D03*
X522084Y243500D03*
Y246500D03*
X525084Y243500D03*
Y246500D03*
X528084Y243500D03*
Y246500D03*
Y290900D03*
Y287900D03*
X525084D03*
Y290900D03*
X522084D03*
Y287900D03*
X531084Y68900D03*
Y65900D03*
Y290900D03*
Y287900D03*
X645784Y43500D03*
X648784D03*
X645784Y40500D03*
X648784D03*
X645784Y99000D03*
X648784D03*
X645784Y96000D03*
X648784D03*
X641000Y261500D03*
X651784Y43500D03*
Y40500D03*
X657784D03*
X654784D03*
X657784Y43500D03*
X654784D03*
X651784Y99000D03*
Y96000D03*
X657784D03*
X654784D03*
X657784Y99000D03*
X654784D03*
X693863Y189760D03*
X688900Y184260D03*
X704200Y206569D03*
X696613Y324032D03*
X693904D03*
X736554Y131056D03*
Y128056D03*
X739554Y131056D03*
Y128056D03*
X742554D03*
X732100Y185000D03*
X729100D03*
X726100D03*
X720100D03*
X723100D03*
X726100Y188000D03*
X729100D03*
X732100D03*
X723100D03*
X720100D03*
X726000Y231500D03*
X729000D03*
X723000D03*
X720000D03*
X732000D03*
Y228500D03*
X720000D03*
X723000D03*
X726000D03*
X729000D03*
X730600Y270000D03*
X727600D03*
X742554Y131056D03*
X749600Y185000D03*
X752600D03*
X755600D03*
X758600D03*
X746600Y188000D03*
X758600D03*
X755600D03*
X752600D03*
X749600D03*
X746600Y185000D03*
X758500Y231500D03*
X746500D03*
X755500D03*
X752500D03*
X749500D03*
X746500Y228500D03*
X755500D03*
X752500D03*
X749500D03*
X758500D03*
X880500Y369500D03*
X983500Y185000D03*
Y188000D03*
X980500Y185000D03*
X974500D03*
X977500D03*
X980500Y188000D03*
X977500D03*
X974500D03*
Y231500D03*
X977500D03*
X983500D03*
X980500D03*
X983500Y228500D03*
X980500D03*
X977500D03*
X974500D03*
X990954Y131056D03*
Y128056D03*
X993954Y131056D03*
Y128056D03*
X996954D03*
Y131056D03*
X986500Y185000D03*
Y188000D03*
X1004000Y185000D03*
X1001000Y188000D03*
X1004000D03*
X1007000Y185000D03*
X1010000D03*
X1013000D03*
Y188000D03*
X1010000D03*
X1007000D03*
X1001000Y185000D03*
X1004000Y231500D03*
X1007000D03*
X1010000D03*
X1001000D03*
X986500D03*
X1013000D03*
X986500Y228500D03*
X1013000D03*
X1004000D03*
X1007000D03*
X1010000D03*
X1001000D03*
X1030100Y207500D03*
X1032500Y281800D03*
X1029500D03*
X1074500Y43500D03*
Y99000D03*
X1061600Y228000D03*
X1064600D03*
X1073600D03*
X1070600D03*
X1077500Y43500D03*
Y40500D03*
X1074500D03*
X1080500D03*
X1083500D03*
X1086500D03*
X1080500Y43500D03*
X1083500D03*
X1086500D03*
X1077500Y99000D03*
Y96000D03*
X1074500D03*
X1080500D03*
X1083500D03*
X1086500D03*
X1080500Y99000D03*
X1083500D03*
X1086500D03*
X1101500Y268500D03*
X1103661Y307700D03*
X1118500Y283000D03*
X1106661Y307700D03*
X1106000Y364500D03*
X1112500Y364700D03*
X1122000Y366240D03*
X1155366Y38982D03*
X1152366D03*
X1158366D03*
X1161366D03*
X1143500Y251500D03*
X1135000Y366500D03*
X1139000D03*
X1176100Y105800D03*
Y108800D03*
X1182100Y105800D03*
Y108800D03*
X1179100D03*
Y105800D03*
X1176100Y111800D03*
Y114800D03*
Y117800D03*
X1182100Y111800D03*
Y114800D03*
Y117800D03*
X1179100D03*
Y114800D03*
Y111800D03*
X1176100Y126800D03*
Y123800D03*
Y120800D03*
X1182100Y126800D03*
Y123800D03*
Y120800D03*
X1179100D03*
Y123800D03*
Y126800D03*
X1176100Y239000D03*
X1171600Y238000D03*
X1179100Y239000D03*
X1182100D03*
X1176100Y254000D03*
Y251000D03*
Y248000D03*
Y245000D03*
Y257000D03*
Y260000D03*
Y242000D03*
X1171600Y241500D03*
X1179100Y242000D03*
Y260000D03*
Y257000D03*
Y245000D03*
Y248000D03*
Y251000D03*
Y254000D03*
X1182100D03*
Y251000D03*
Y248000D03*
Y245000D03*
Y257000D03*
Y260000D03*
Y242000D03*
X1178500Y368740D03*
X1223866Y38482D03*
X1220866D03*
X1225930Y359148D03*
X1226866Y38482D03*
X1229866D03*
X1237200Y205100D03*
Y202100D03*
Y199100D03*
X1240200D03*
Y202100D03*
Y205100D03*
X1234200Y249500D03*
Y246500D03*
Y243500D03*
X1237200Y249500D03*
Y246500D03*
Y243500D03*
X1240200D03*
Y246500D03*
Y249500D03*
Y293900D03*
Y290900D03*
Y287900D03*
X1237200D03*
Y290900D03*
Y293900D03*
X1234200Y287900D03*
Y290900D03*
Y293900D03*
X1231200D03*
Y290900D03*
Y287900D03*
X1242930Y359148D03*
Y356148D03*
X1245930Y359148D03*
Y356148D03*
X1248930Y359148D03*
Y356148D03*
X1231930D03*
Y359148D03*
X1228930Y356148D03*
Y359148D03*
X1225930Y356148D03*
X1253930Y379648D03*
X1250930D03*
X1247930D03*
X1264366Y38482D03*
X1261366D03*
X1267366D03*
X1270366D03*
X1260340Y359284D03*
Y356284D03*
X1263340Y359284D03*
Y356284D03*
X1266340Y359284D03*
Y356284D03*
X1286113Y378312D03*
X1265340Y379784D03*
X1268340D03*
X1271340D03*
X1307700Y78900D03*
Y81900D03*
X1310700D03*
Y78900D03*
X1313700Y81900D03*
Y78900D03*
X1307700Y84900D03*
Y87900D03*
X1310700D03*
Y84900D03*
X1313700Y87900D03*
Y84900D03*
X1307700Y90900D03*
X1310700D03*
X1313700D03*
X1307700Y123300D03*
Y126300D03*
X1310700D03*
Y123300D03*
X1313700Y126300D03*
Y123300D03*
X1307700Y129300D03*
Y132300D03*
Y135300D03*
X1310700D03*
Y132300D03*
Y129300D03*
X1313700Y135300D03*
Y132300D03*
Y129300D03*
Y167700D03*
Y170700D03*
Y173700D03*
Y176700D03*
X1310700Y167700D03*
Y170700D03*
Y173700D03*
Y176700D03*
X1307700D03*
Y173700D03*
Y170700D03*
Y167700D03*
X1313700Y179700D03*
X1310700D03*
X1307700D03*
Y212100D03*
Y215100D03*
X1310700D03*
Y212100D03*
X1313700Y215100D03*
Y212100D03*
X1307700Y218100D03*
Y221100D03*
Y224100D03*
X1310700D03*
Y221100D03*
Y218100D03*
X1313700Y224100D03*
Y221100D03*
Y218100D03*
X1307700Y256500D03*
Y259500D03*
X1310700D03*
Y256500D03*
X1313700Y259500D03*
Y256500D03*
X1307700Y262500D03*
Y265500D03*
Y268500D03*
X1310700D03*
Y265500D03*
Y262500D03*
X1313700Y268500D03*
Y265500D03*
Y262500D03*
X1307700Y300900D03*
Y303900D03*
X1310700D03*
Y300900D03*
X1313700Y303900D03*
Y300900D03*
X1307700Y306900D03*
Y309900D03*
Y312900D03*
X1310700D03*
Y309900D03*
Y306900D03*
X1313700Y309900D03*
Y306900D03*
X1286113Y375312D03*
X1289113Y378312D03*
Y375312D03*
X1292113Y378312D03*
Y375312D03*
Y372312D03*
X1289113D03*
X1316700Y81900D03*
Y78900D03*
X1319700Y81900D03*
Y78900D03*
X1316700Y87900D03*
Y84900D03*
X1319700Y87900D03*
Y84900D03*
X1316700Y90900D03*
X1319700D03*
X1316700Y126300D03*
Y123300D03*
X1319700Y126300D03*
Y123300D03*
X1316700Y135300D03*
Y132300D03*
Y129300D03*
X1319700Y135300D03*
Y132300D03*
Y129300D03*
Y167700D03*
Y170700D03*
Y173700D03*
Y176700D03*
X1316700Y167700D03*
Y170700D03*
Y173700D03*
Y176700D03*
Y215100D03*
Y212100D03*
X1319700Y215100D03*
Y212100D03*
X1316700Y224100D03*
Y221100D03*
Y218100D03*
X1319700Y224100D03*
Y221100D03*
Y218100D03*
X1316700Y259500D03*
Y256500D03*
X1319700Y259500D03*
Y256500D03*
X1316700Y268500D03*
Y265500D03*
Y262500D03*
X1319700Y268500D03*
Y265500D03*
Y262500D03*
X1316700Y303900D03*
Y300900D03*
X1319700Y303900D03*
Y300900D03*
X1316700Y306900D03*
X1406230Y21076D03*
Y18076D03*
Y15076D03*
X1403230Y21076D03*
Y18076D03*
Y15076D03*
X1400230Y21076D03*
Y18076D03*
Y15076D03*
X1397230D03*
Y18076D03*
Y21076D03*
X1412230D03*
Y18076D03*
Y15076D03*
X1409230Y21076D03*
Y18076D03*
Y15076D03*
X1764000Y107000D03*
X1763500Y113000D03*
X1751289Y345227D03*
X1747416Y351817D03*
X1747235Y355989D03*
Y359564D03*
Y363689D03*
Y367264D03*
Y371389D03*
Y374964D03*
X1773500Y121000D03*
X1776100Y361500D03*
Y371500D03*
Y368500D03*
X1776140Y364405D03*
X1844500Y416500D03*
X1847500Y437000D03*
G54D33*
X802087Y145984D03*
X792087D03*
X802087Y135984D03*
X792087D03*
X802087Y180984D03*
X792087D03*
X802087Y170984D03*
X792087D03*
X802087Y230984D03*
X792087D03*
X802087Y220984D03*
X792087D03*
X802087Y265984D03*
X792087D03*
X802087Y255984D03*
X792087D03*
X822087Y145984D03*
X812087D03*
X822087Y135984D03*
X812087D03*
X822087Y180984D03*
X812087D03*
X822087Y170984D03*
X812087D03*
X822087Y230984D03*
X812087D03*
X822087Y220984D03*
X812087D03*
X822087Y265984D03*
X812087D03*
X822087Y255984D03*
X812087D03*
X920197Y145984D03*
X910197D03*
X920197Y135984D03*
X910197D03*
X920197Y180984D03*
X910197D03*
X920197Y170984D03*
X910197D03*
X920197Y230984D03*
X910197D03*
X920197Y220984D03*
X910197D03*
X920197Y265984D03*
X910197D03*
X920197Y255984D03*
X910197D03*
X940197Y145984D03*
X930197D03*
X940197Y135984D03*
X930197D03*
X940197Y180984D03*
X930197D03*
X940197Y170984D03*
X930197D03*
X940197Y230984D03*
X930197D03*
X940197Y220984D03*
X930197D03*
X940197Y265984D03*
X930197D03*
X940197Y255984D03*
X930197D03*
G54D36*
X822087Y88484D03*
Y313484D03*
X940197Y88484D03*
Y313484D03*
G54D16*
X59055Y236614D03*
Y411594D03*
X1673228Y236614D03*
Y411614D03*
G54D46*
X1835739Y99212D03*
X1835738Y481693D03*
G54D12*
X32284Y541339D03*
X59055Y498032D03*
X1673228D03*
X1700000Y541339D03*
G54D39*
X866400Y372200D03*
G54D30*
X668314Y570042D03*
G54D32*
X668420Y598187D03*
%LPC*%
G75*
G54D20*
X166785Y230000D03*
Y310000D03*
Y390000D03*
Y470000D03*
Y550000D03*
X243785Y230000D03*
Y310000D03*
Y390000D03*
Y470000D03*
Y550000D03*
X1488500Y230000D03*
Y310000D03*
Y390000D03*
Y470000D03*
Y550000D03*
X1565500Y230000D03*
Y310000D03*
Y390000D03*
Y470000D03*
Y550000D03*
G54D50*
G01X166785Y230000D02*
X169956Y226829D01*
G01X163614Y233171D02*
X166785Y230000D01*
G01D02*
X169956Y233171D01*
G01X163614Y226829D02*
X166785Y230000D01*
G01Y310000D02*
X169956Y306829D01*
G01X163614Y313171D02*
X166785Y310000D01*
G01D02*
X169956Y313171D01*
G01X163614Y306829D02*
X166785Y310000D01*
G01X163614Y386829D02*
X166785Y390000D01*
G01D02*
X169956Y386829D01*
G01X163614Y393171D02*
X166785Y390000D01*
G01D02*
X169956Y393171D01*
G01X166785Y470000D02*
X169956Y466829D01*
G01X163614Y473171D02*
X166785Y470000D01*
G01D02*
X169956Y473171D01*
G01X163614Y466829D02*
X166785Y470000D01*
G01X163614Y546829D02*
X166785Y550000D01*
G01D02*
X169956Y553171D01*
G01X163614D02*
X166785Y550000D01*
G01D02*
X169956Y546829D01*
G01X243785Y230000D02*
X246956Y226829D01*
G01X240614Y233171D02*
X243785Y230000D01*
G01D02*
X246956Y233171D01*
G01X240614Y226829D02*
X243785Y230000D01*
G01Y310000D02*
X246956Y306829D01*
G01X240614Y313171D02*
X243785Y310000D01*
G01D02*
X246956Y313171D01*
G01X240614Y306829D02*
X243785Y310000D01*
G01Y390000D02*
X246956Y386829D01*
G01X240614Y393171D02*
X243785Y390000D01*
G01D02*
X246956Y393171D01*
G01X240614Y386829D02*
X243785Y390000D01*
G01Y470000D02*
X246956Y466829D01*
G01X240614Y473171D02*
X243785Y470000D01*
G01D02*
X246956Y473171D01*
G01X240614Y466829D02*
X243785Y470000D01*
G01Y550000D02*
X246956Y546829D01*
G01X240614Y553171D02*
X243785Y550000D01*
G01D02*
X246956Y553171D01*
G01X240614Y546829D02*
X243785Y550000D01*
G01X1488500Y230000D02*
X1491671Y226829D01*
G01X1485329Y233171D02*
X1488500Y230000D01*
G01D02*
X1491671Y233171D01*
G01X1485329Y226829D02*
X1488500Y230000D01*
G01Y310000D02*
X1491671Y306829D01*
G01X1485329Y313171D02*
X1488500Y310000D01*
G01D02*
X1491671Y313171D01*
G01X1485329Y306829D02*
X1488500Y310000D01*
G01Y390000D02*
X1491671Y386829D01*
G01X1485329Y393171D02*
X1488500Y390000D01*
G01D02*
X1491671Y393171D01*
G01X1485329Y386829D02*
X1488500Y390000D01*
G01Y470000D02*
X1491671Y466829D01*
G01X1485329Y473171D02*
X1488500Y470000D01*
G01D02*
X1491671Y473171D01*
G01X1485329Y466829D02*
X1488500Y470000D01*
G01Y550000D02*
X1491671Y546829D01*
G01X1485329Y553171D02*
X1488500Y550000D01*
G01D02*
X1491671Y553171D01*
G01X1485329Y546829D02*
X1488500Y550000D01*
G01X1565500Y230000D02*
X1568671Y226829D01*
G01X1562329Y233171D02*
X1565500Y230000D01*
G01D02*
X1568671Y233171D01*
G01X1562329Y226829D02*
X1565500Y230000D01*
G01Y310000D02*
X1568671Y306829D01*
G01X1562329Y313171D02*
X1565500Y310000D01*
G01D02*
X1568671Y313171D01*
G01X1562329Y306829D02*
X1565500Y310000D01*
G01Y390000D02*
X1568671Y386829D01*
G01X1562329Y393171D02*
X1565500Y390000D01*
G01D02*
X1568671Y393171D01*
G01X1562329Y386829D02*
X1565500Y390000D01*
G01Y470000D02*
X1568671Y466829D01*
G01X1562329Y473171D02*
X1565500Y470000D01*
G01D02*
X1568671Y473171D01*
G01X1562329Y466829D02*
X1565500Y470000D01*
G01Y550000D02*
X1568671Y546829D01*
G01X1562329Y553171D02*
X1565500Y550000D01*
G01D02*
X1568671Y553171D01*
G01X1562329Y546829D02*
X1565500Y550000D01*
G54D51*
G01X-457143Y-1211429D02*
Y2242857D01*
X4308572D01*
Y-1211429D01*
X-457143D01*
G01X37000Y-995000D02*
Y-1070000D01*
X537000D01*
Y-995000D01*
X37000D01*
G01X49000Y-1060000D02*
Y-1065000D01*
G01X47543Y-1060000D02*
X50457D01*
G01X55367Y-1065000D02*
X52833D01*
Y-1060000D01*
X55367D01*
G01X54353Y-1062417D02*
X52833D01*
G01X57933Y-1060000D02*
Y-1065000D01*
X60467D01*
G01X64300Y-1065167D02*
X64173Y-1065083D01*
Y-1064917D01*
X64300Y-1064833D01*
X64427Y-1064917D01*
Y-1065083D01*
X64300Y-1065167D01*
G01Y-1062917D02*
X64173Y-1062833D01*
Y-1062667D01*
X64300Y-1062583D01*
X64427Y-1062667D01*
Y-1062833D01*
X64300Y-1062917D01*
G01X69083Y-1066667D02*
X68450Y-1065833D01*
X68133Y-1065000D01*
Y-1061667D01*
X68450Y-1060833D01*
X69083Y-1060000D01*
G01X74500D02*
X73993Y-1060167D01*
X73613Y-1060583D01*
X73360Y-1061083D01*
X73170Y-1061750D01*
X73107Y-1062500D01*
X73170Y-1063250D01*
X73360Y-1063917D01*
X73613Y-1064417D01*
X73993Y-1064833D01*
X74500Y-1065000D01*
X75007Y-1064833D01*
X75387Y-1064417D01*
X75640Y-1063917D01*
X75830Y-1063250D01*
X75893Y-1062500D01*
X75830Y-1061750D01*
X75640Y-1061083D01*
X75387Y-1060583D01*
X75007Y-1060167D01*
X74500Y-1060000D01*
G01X78207Y-1064000D02*
X78587Y-1064583D01*
X79093Y-1064917D01*
X79663Y-1065000D01*
X80170Y-1064917D01*
X80677Y-1064500D01*
X80993Y-1064000D01*
X81057Y-1063500D01*
X80930Y-1062917D01*
X80487Y-1062500D01*
X80043Y-1062333D01*
X79473D01*
G01X80043D02*
X80423Y-1062083D01*
X80740Y-1061667D01*
X80867Y-1061167D01*
X80740Y-1060667D01*
X80423Y-1060250D01*
X79853Y-1060000D01*
X79283Y-1060083D01*
X78713Y-1060417D01*
G01X85017Y-1066667D02*
X85650Y-1065833D01*
X85967Y-1065000D01*
Y-1061667D01*
X85650Y-1060833D01*
X85017Y-1060000D01*
G01X88407Y-1064000D02*
X88787Y-1064583D01*
X89293Y-1064917D01*
X89863Y-1065000D01*
X90370Y-1064917D01*
X90877Y-1064500D01*
X91193Y-1064000D01*
X91257Y-1063500D01*
X91130Y-1062917D01*
X90687Y-1062500D01*
X90243Y-1062333D01*
X89673D01*
G01X90243D02*
X90623Y-1062083D01*
X90940Y-1061667D01*
X91067Y-1061167D01*
X90940Y-1060667D01*
X90623Y-1060250D01*
X90053Y-1060000D01*
X89483Y-1060083D01*
X88913Y-1060417D01*
G01X93697Y-1060833D02*
X94077Y-1060333D01*
X94520Y-1060083D01*
X95027Y-1060000D01*
X95660Y-1060167D01*
X96103Y-1060583D01*
X96230Y-1061083D01*
X96167Y-1061583D01*
X95913Y-1062000D01*
X94647Y-1062833D01*
X94077Y-1063417D01*
X93697Y-1064250D01*
X93570Y-1065000D01*
X96230D01*
G01X99873D02*
X100000Y-1063917D01*
X100190Y-1063000D01*
X100443Y-1062167D01*
X100760Y-1061250D01*
X101267Y-1060000D01*
X98733D01*
G01X104277Y-1063333D02*
X105923D01*
G01X108997Y-1060833D02*
X109377Y-1060333D01*
X109820Y-1060083D01*
X110327Y-1060000D01*
X110960Y-1060167D01*
X111403Y-1060583D01*
X111530Y-1061083D01*
X111467Y-1061583D01*
X111213Y-1062000D01*
X109947Y-1062833D01*
X109377Y-1063417D01*
X108997Y-1064250D01*
X108870Y-1065000D01*
X111530D01*
G01X113907Y-1064000D02*
X114287Y-1064583D01*
X114793Y-1064917D01*
X115363Y-1065000D01*
X115870Y-1064917D01*
X116377Y-1064500D01*
X116693Y-1064000D01*
X116757Y-1063500D01*
X116630Y-1062917D01*
X116187Y-1062500D01*
X115743Y-1062333D01*
X115173D01*
G01X115743D02*
X116123Y-1062083D01*
X116440Y-1061667D01*
X116567Y-1061167D01*
X116440Y-1060667D01*
X116123Y-1060250D01*
X115553Y-1060000D01*
X114983Y-1060083D01*
X114413Y-1060417D01*
G01X121160Y-1065000D02*
Y-1060000D01*
X118817Y-1063583D01*
X121983D01*
G01X124107Y-1064250D02*
X124487Y-1064667D01*
X124930Y-1064917D01*
X125500Y-1065000D01*
X126070Y-1064833D01*
X126513Y-1064500D01*
X126830Y-1063917D01*
X126893Y-1063250D01*
X126767Y-1062583D01*
X126450Y-1062167D01*
X126007Y-1061833D01*
X125563Y-1061750D01*
X125120Y-1061833D01*
X124550Y-1062167D01*
X124740Y-1060000D01*
X126450D01*
G01X134497Y-1065000D02*
Y-1060000D01*
X136903D01*
G01X136017Y-1062417D02*
X134497D01*
G01X139217Y-1065000D02*
X140800Y-1060000D01*
X142383Y-1065000D01*
G01X141813Y-1063250D02*
X139787D01*
G01X144570Y-1065000D02*
X147230Y-1060000D01*
G01X144570D02*
X147230Y-1065000D01*
G01X151000Y-1065167D02*
X150873Y-1065083D01*
Y-1064917D01*
X151000Y-1064833D01*
X151127Y-1064917D01*
Y-1065083D01*
X151000Y-1065167D01*
G01Y-1062917D02*
X150873Y-1062833D01*
Y-1062667D01*
X151000Y-1062583D01*
X151127Y-1062667D01*
Y-1062833D01*
X151000Y-1062917D01*
G01X155783Y-1066667D02*
X155150Y-1065833D01*
X154833Y-1065000D01*
Y-1061667D01*
X155150Y-1060833D01*
X155783Y-1060000D01*
G01X161200D02*
X160693Y-1060167D01*
X160313Y-1060583D01*
X160060Y-1061083D01*
X159870Y-1061750D01*
X159807Y-1062500D01*
X159870Y-1063250D01*
X160060Y-1063917D01*
X160313Y-1064417D01*
X160693Y-1064833D01*
X161200Y-1065000D01*
X161707Y-1064833D01*
X162087Y-1064417D01*
X162340Y-1063917D01*
X162530Y-1063250D01*
X162593Y-1062500D01*
X162530Y-1061750D01*
X162340Y-1061083D01*
X162087Y-1060583D01*
X161707Y-1060167D01*
X161200Y-1060000D01*
G01X164907Y-1064000D02*
X165287Y-1064583D01*
X165793Y-1064917D01*
X166363Y-1065000D01*
X166870Y-1064917D01*
X167377Y-1064500D01*
X167693Y-1064000D01*
X167757Y-1063500D01*
X167630Y-1062917D01*
X167187Y-1062500D01*
X166743Y-1062333D01*
X166173D01*
G01X166743D02*
X167123Y-1062083D01*
X167440Y-1061667D01*
X167567Y-1061167D01*
X167440Y-1060667D01*
X167123Y-1060250D01*
X166553Y-1060000D01*
X165983Y-1060083D01*
X165413Y-1060417D01*
G01X171717Y-1066667D02*
X172350Y-1065833D01*
X172667Y-1065000D01*
Y-1061667D01*
X172350Y-1060833D01*
X171717Y-1060000D01*
G01X175107Y-1064000D02*
X175487Y-1064583D01*
X175993Y-1064917D01*
X176563Y-1065000D01*
X177070Y-1064917D01*
X177577Y-1064500D01*
X177893Y-1064000D01*
X177957Y-1063500D01*
X177830Y-1062917D01*
X177387Y-1062500D01*
X176943Y-1062333D01*
X176373D01*
G01X176943D02*
X177323Y-1062083D01*
X177640Y-1061667D01*
X177767Y-1061167D01*
X177640Y-1060667D01*
X177323Y-1060250D01*
X176753Y-1060000D01*
X176183Y-1060083D01*
X175613Y-1060417D01*
G01X180523Y-1064417D02*
X180967Y-1064833D01*
X181473Y-1065000D01*
X181980Y-1064833D01*
X182423Y-1064333D01*
X182740Y-1063583D01*
X182867Y-1062833D01*
Y-1061917D01*
X182740Y-1061167D01*
X182423Y-1060500D01*
X182043Y-1060167D01*
X181600Y-1060000D01*
X181093Y-1060167D01*
X180713Y-1060500D01*
X180460Y-1061000D01*
X180333Y-1061667D01*
X180460Y-1062250D01*
X180777Y-1062833D01*
X181157Y-1063167D01*
X181600Y-1063250D01*
X182107Y-1063083D01*
X182487Y-1062667D01*
X182867Y-1061917D01*
G01X186573Y-1065000D02*
X186700Y-1063917D01*
X186890Y-1063000D01*
X187143Y-1062167D01*
X187460Y-1061250D01*
X187967Y-1060000D01*
X185433D01*
G01X190977Y-1063333D02*
X192623D01*
G01X195507Y-1064000D02*
X195887Y-1064583D01*
X196393Y-1064917D01*
X196963Y-1065000D01*
X197470Y-1064917D01*
X197977Y-1064500D01*
X198293Y-1064000D01*
X198357Y-1063500D01*
X198230Y-1062917D01*
X197787Y-1062500D01*
X197343Y-1062333D01*
X196773D01*
G01X197343D02*
X197723Y-1062083D01*
X198040Y-1061667D01*
X198167Y-1061167D01*
X198040Y-1060667D01*
X197723Y-1060250D01*
X197153Y-1060000D01*
X196583Y-1060083D01*
X196013Y-1060417D01*
G01X200797Y-1062917D02*
X201240Y-1062333D01*
X201620Y-1062000D01*
X202127Y-1061833D01*
X202570Y-1062000D01*
X202887Y-1062333D01*
X203140Y-1062833D01*
X203203Y-1063417D01*
X203140Y-1063917D01*
X202887Y-1064417D01*
X202507Y-1064833D01*
X202063Y-1065000D01*
X201557Y-1064833D01*
X201113Y-1064333D01*
X200860Y-1063583D01*
X200797Y-1062750D01*
X200923Y-1061667D01*
X201113Y-1061083D01*
X201430Y-1060500D01*
X201873Y-1060083D01*
X202317Y-1060000D01*
X202760Y-1060167D01*
X203077Y-1060583D01*
G01X207100Y-1065000D02*
Y-1060000D01*
X206340Y-1061000D01*
G01Y-1065000D02*
X207860D01*
G01X212960D02*
Y-1060000D01*
X210617Y-1063583D01*
X213783D01*
G01X232000Y-995000D02*
Y-1070000D01*
G01Y-1045000D02*
X335000D01*
Y-1020000D01*
G01X232000D02*
X335000D01*
G01X337000Y-995000D02*
Y-1070000D01*
G01X335000Y-995000D02*
Y-1070000D01*
G01X342507Y-1055000D02*
Y-1050000D01*
X343773D01*
X344280Y-1050250D01*
X344660Y-1050583D01*
X344977Y-1051083D01*
X345230Y-1051667D01*
X345293Y-1052500D01*
X345230Y-1053333D01*
X344977Y-1053917D01*
X344660Y-1054417D01*
X344280Y-1054750D01*
X343773Y-1055000D01*
X342507D01*
G01X347417D02*
X349000Y-1050000D01*
X350583Y-1055000D01*
G01X350013Y-1053250D02*
X347987D01*
G01X354100Y-1050000D02*
Y-1055000D01*
G01X352643Y-1050000D02*
X355557D01*
G01X360467Y-1055000D02*
X357933D01*
Y-1050000D01*
X360467D01*
G01X359453Y-1052417D02*
X357933D01*
G01X364300Y-1055167D02*
X364173Y-1055083D01*
Y-1054917D01*
X364300Y-1054833D01*
X364427Y-1054917D01*
Y-1055083D01*
X364300Y-1055167D01*
G01Y-1052917D02*
X364173Y-1052833D01*
Y-1052667D01*
X364300Y-1052583D01*
X364427Y-1052667D01*
Y-1052833D01*
X364300Y-1052917D01*
G01X337000Y-1045000D02*
X537000D01*
G01X342633Y-1030000D02*
Y-1025000D01*
X344153D01*
X344660Y-1025250D01*
X345040Y-1025833D01*
X345167Y-1026500D01*
X345040Y-1027167D01*
X344723Y-1027667D01*
X344153Y-1027917D01*
X342633D01*
G01X347860Y-1030167D02*
X350140Y-1025000D01*
G01X352643Y-1030000D02*
Y-1025000D01*
X355557Y-1030000D01*
Y-1025000D01*
G01X359200Y-1030167D02*
X359073Y-1030083D01*
Y-1029917D01*
X359200Y-1029833D01*
X359327Y-1029917D01*
Y-1030083D01*
X359200Y-1030167D01*
G01Y-1027917D02*
X359073Y-1027833D01*
Y-1027667D01*
X359200Y-1027583D01*
X359327Y-1027667D01*
Y-1027833D01*
X359200Y-1027917D01*
G01X342633Y-1005000D02*
Y-1000000D01*
X344153D01*
X344660Y-1000250D01*
X345040Y-1000833D01*
X345167Y-1001500D01*
X345040Y-1002167D01*
X344723Y-1002667D01*
X344153Y-1002917D01*
X342633D01*
G01X347733Y-1005000D02*
Y-1000000D01*
X349317D01*
X349823Y-1000250D01*
X350140Y-1000583D01*
X350267Y-1001250D01*
X350140Y-1001917D01*
X349760Y-1002333D01*
X349317Y-1002583D01*
X347733D01*
G01X349317D02*
X350267Y-1005000D01*
G01X354100D02*
X353593Y-1004917D01*
X353150Y-1004583D01*
X352770Y-1004083D01*
X352517Y-1003500D01*
X352390Y-1002833D01*
Y-1002167D01*
X352517Y-1001500D01*
X352770Y-1000917D01*
X353150Y-1000417D01*
X353593Y-1000083D01*
X354100Y-1000000D01*
X354607Y-1000083D01*
X355050Y-1000417D01*
X355430Y-1000917D01*
X355683Y-1001500D01*
X355810Y-1002167D01*
Y-1002833D01*
X355683Y-1003500D01*
X355430Y-1004083D01*
X355050Y-1004583D01*
X354607Y-1004917D01*
X354100Y-1005000D01*
G01X357933Y-1004000D02*
X358250Y-1004500D01*
X358630Y-1004833D01*
X359073Y-1005000D01*
X359580Y-1004833D01*
X359960Y-1004500D01*
X360340Y-1004000D01*
X360467Y-1003333D01*
Y-1000000D01*
G01X365567Y-1005000D02*
X363033D01*
Y-1000000D01*
X365567D01*
G01X364553Y-1002417D02*
X363033D01*
G01X370793Y-1000417D02*
X370413Y-1000167D01*
X369970Y-1000000D01*
X369463D01*
X368893Y-1000250D01*
X368450Y-1000667D01*
X368133Y-1001167D01*
X367880Y-1002000D01*
X367817Y-1002750D01*
X367943Y-1003500D01*
X368133Y-1004000D01*
X368513Y-1004500D01*
X368957Y-1004833D01*
X369400Y-1005000D01*
X369843D01*
X370287Y-1004833D01*
X370667Y-1004583D01*
X370983Y-1004250D01*
G01X374500Y-1000000D02*
Y-1005000D01*
G01X373043Y-1000000D02*
X375957D01*
G01X379600Y-1005167D02*
X379473Y-1005083D01*
Y-1004917D01*
X379600Y-1004833D01*
X379727Y-1004917D01*
Y-1005083D01*
X379600Y-1005167D01*
G01Y-1002917D02*
X379473Y-1002833D01*
Y-1002667D01*
X379600Y-1002583D01*
X379727Y-1002667D01*
Y-1002833D01*
X379600Y-1002917D01*
G01X337000Y-1020000D02*
X537000D01*
G01X452000Y-1045000D02*
Y-1070000D01*
G01X454633Y-1047500D02*
Y-1052500D01*
X457167D01*
G01X460240Y-1047500D02*
X461760D01*
G01X461000D02*
Y-1052500D01*
G01X460240D02*
X461760D01*
G01X466607Y-1049833D02*
X466860Y-1049583D01*
X467050Y-1049167D01*
X467177Y-1048583D01*
X467050Y-1048083D01*
X466797Y-1047750D01*
X466353Y-1047500D01*
X464643D01*
Y-1052500D01*
X466733D01*
X467177Y-1052167D01*
X467430Y-1051667D01*
X467557Y-1051083D01*
X467430Y-1050500D01*
X467050Y-1050000D01*
X466607Y-1049833D01*
X464643D01*
G01X471200Y-1052667D02*
X471073Y-1052583D01*
Y-1052417D01*
X471200Y-1052333D01*
X471327Y-1052417D01*
Y-1052583D01*
X471200Y-1052667D01*
G01Y-1050417D02*
X471073Y-1050333D01*
Y-1050167D01*
X471200Y-1050083D01*
X471327Y-1050167D01*
Y-1050333D01*
X471200Y-1050417D01*
G01X495000Y-1045000D02*
Y-1070000D01*
G01X498900Y-1047500D02*
Y-1052500D01*
G01X497443Y-1047500D02*
X500357D01*
G01X504000Y-1052500D02*
X503620Y-1052417D01*
X503240Y-1052083D01*
X502987Y-1051500D01*
X502860Y-1050833D01*
X502987Y-1050167D01*
X503240Y-1049583D01*
X503620Y-1049250D01*
X504000Y-1049167D01*
X504380Y-1049250D01*
X504760Y-1049583D01*
X505013Y-1050167D01*
X505077Y-1050833D01*
X505013Y-1051500D01*
X504760Y-1052083D01*
X504380Y-1052417D01*
X504000Y-1052500D01*
G01X509100D02*
X508720Y-1052417D01*
X508340Y-1052083D01*
X508087Y-1051500D01*
X507960Y-1050833D01*
X508087Y-1050167D01*
X508340Y-1049583D01*
X508720Y-1049250D01*
X509100Y-1049167D01*
X509480Y-1049250D01*
X509860Y-1049583D01*
X510113Y-1050167D01*
X510177Y-1050833D01*
X510113Y-1051500D01*
X509860Y-1052083D01*
X509480Y-1052417D01*
X509100Y-1052500D01*
G01X514200D02*
Y-1047500D01*
G01X519300Y-1052667D02*
X519173Y-1052583D01*
Y-1052417D01*
X519300Y-1052333D01*
X519427Y-1052417D01*
Y-1052583D01*
X519300Y-1052667D01*
G01Y-1050417D02*
X519173Y-1050333D01*
Y-1050167D01*
X519300Y-1050083D01*
X519427Y-1050167D01*
Y-1050333D01*
X519300Y-1050417D01*
G01X495000Y-1020000D02*
Y-1045000D01*
G01X497633Y-1027500D02*
Y-1022500D01*
X499217D01*
X499723Y-1022750D01*
X500040Y-1023083D01*
X500167Y-1023750D01*
X500040Y-1024417D01*
X499660Y-1024833D01*
X499217Y-1025083D01*
X497633D01*
G01X499217D02*
X500167Y-1027500D01*
G01X505267D02*
X502733D01*
Y-1022500D01*
X505267D01*
G01X504253Y-1024917D02*
X502733D01*
G01X507517Y-1022500D02*
X509100Y-1027500D01*
X510683Y-1022500D01*
G01X514200Y-1027667D02*
X514073Y-1027583D01*
Y-1027417D01*
X514200Y-1027333D01*
X514327Y-1027417D01*
Y-1027583D01*
X514200Y-1027667D01*
G01Y-1025417D02*
X514073Y-1025333D01*
Y-1025167D01*
X514200Y-1025083D01*
X514327Y-1025167D01*
Y-1025333D01*
X514200Y-1025417D01*
G01X503013Y-1073167D02*
X503120Y-1073042D01*
X503200Y-1072833D01*
X503253Y-1072542D01*
X503200Y-1072292D01*
X503093Y-1072125D01*
X502907Y-1072000D01*
X502187D01*
Y-1074500D01*
X503067D01*
X503253Y-1074333D01*
X503360Y-1074083D01*
X503413Y-1073792D01*
X503360Y-1073500D01*
X503200Y-1073250D01*
X503013Y-1073167D01*
X502187D01*
G01X505480Y-1074500D02*
Y-1072833D01*
G01Y-1073125D02*
X505373Y-1072958D01*
X505213Y-1072875D01*
X505027Y-1072833D01*
X504840Y-1072917D01*
X504680Y-1073083D01*
X504573Y-1073333D01*
X504520Y-1073667D01*
X504573Y-1074000D01*
X504680Y-1074250D01*
X504840Y-1074417D01*
X505027Y-1074500D01*
X505213Y-1074458D01*
X505373Y-1074333D01*
X505480Y-1074167D01*
G01X506800Y-1074208D02*
X506933Y-1074375D01*
X507120Y-1074500D01*
X507280D01*
X507440Y-1074417D01*
X507547Y-1074292D01*
X507600Y-1074125D01*
X507573Y-1073875D01*
X507467Y-1073750D01*
X506987Y-1073500D01*
X506880Y-1073208D01*
X506933Y-1073000D01*
X507040Y-1072875D01*
X507200Y-1072833D01*
X507360Y-1072875D01*
X507520Y-1073000D01*
G01X509000Y-1073375D02*
X509853D01*
X509773Y-1073083D01*
X509640Y-1072917D01*
X509453Y-1072833D01*
X509267Y-1072875D01*
X509107Y-1073000D01*
X509000Y-1073292D01*
X508947Y-1073542D01*
Y-1073792D01*
X509000Y-1074042D01*
X509133Y-1074292D01*
X509293Y-1074458D01*
X509480Y-1074500D01*
X509667Y-1074417D01*
X509853Y-1074167D01*
G01X511120Y-1074500D02*
Y-1072000D01*
G01Y-1073250D02*
X511253Y-1073000D01*
X511413Y-1072875D01*
X511573Y-1072833D01*
X511813Y-1072917D01*
X511973Y-1073083D01*
X512080Y-1073375D01*
Y-1073708D01*
X512027Y-1074042D01*
X511920Y-1074292D01*
X511733Y-1074458D01*
X511573Y-1074500D01*
X511413Y-1074458D01*
X511253Y-1074333D01*
X511120Y-1074125D01*
G01X513800Y-1074500D02*
X513640Y-1074458D01*
X513480Y-1074292D01*
X513373Y-1074000D01*
X513320Y-1073667D01*
X513373Y-1073333D01*
X513480Y-1073042D01*
X513640Y-1072875D01*
X513800Y-1072833D01*
X513960Y-1072875D01*
X514120Y-1073042D01*
X514227Y-1073333D01*
X514253Y-1073667D01*
X514227Y-1074000D01*
X514120Y-1074292D01*
X513960Y-1074458D01*
X513800Y-1074500D01*
G01X516480D02*
Y-1072833D01*
G01Y-1073125D02*
X516373Y-1072958D01*
X516213Y-1072875D01*
X516027Y-1072833D01*
X515840Y-1072917D01*
X515680Y-1073083D01*
X515573Y-1073333D01*
X515520Y-1073667D01*
X515573Y-1074000D01*
X515680Y-1074250D01*
X515840Y-1074417D01*
X516027Y-1074500D01*
X516213Y-1074458D01*
X516373Y-1074333D01*
X516480Y-1074167D01*
G01X517827Y-1074500D02*
Y-1072833D01*
G01Y-1073167D02*
X517960Y-1073000D01*
X518093Y-1072875D01*
X518280Y-1072833D01*
X518413Y-1072875D01*
X518573Y-1073000D01*
G01X520880Y-1072000D02*
Y-1074500D01*
G01Y-1074125D02*
X520773Y-1074333D01*
X520613Y-1074458D01*
X520427Y-1074500D01*
X520213Y-1074417D01*
X520053Y-1074208D01*
X519947Y-1073958D01*
X519920Y-1073667D01*
X519947Y-1073375D01*
X520053Y-1073125D01*
X520213Y-1072917D01*
X520427Y-1072833D01*
X520613Y-1072875D01*
X520747Y-1072958D01*
X520880Y-1073125D01*
G01X524267Y-1074500D02*
Y-1072000D01*
X524933D01*
X525147Y-1072125D01*
X525280Y-1072292D01*
X525333Y-1072625D01*
X525280Y-1072958D01*
X525120Y-1073167D01*
X524933Y-1073292D01*
X524267D01*
G01X524933D02*
X525333Y-1074500D01*
G01X526600Y-1073375D02*
X527453D01*
X527373Y-1073083D01*
X527240Y-1072917D01*
X527053Y-1072833D01*
X526867Y-1072875D01*
X526707Y-1073000D01*
X526600Y-1073292D01*
X526547Y-1073542D01*
Y-1073792D01*
X526600Y-1074042D01*
X526733Y-1074292D01*
X526893Y-1074458D01*
X527080Y-1074500D01*
X527267Y-1074417D01*
X527453Y-1074167D01*
G01X528720Y-1072833D02*
X529200Y-1074500D01*
X529680Y-1072833D01*
G01X531400Y-1074583D02*
X531347Y-1074542D01*
Y-1074458D01*
X531400Y-1074417D01*
X531453Y-1074458D01*
Y-1074542D01*
X531400Y-1074583D01*
G01X533600Y-1074500D02*
X533787Y-1074458D01*
X534000Y-1074333D01*
X534133Y-1074125D01*
X534187Y-1073833D01*
X534133Y-1073542D01*
X533973Y-1073292D01*
X533733Y-1073167D01*
X533467D01*
X533307Y-1073083D01*
X533173Y-1072875D01*
X533120Y-1072583D01*
X533200Y-1072292D01*
X533387Y-1072083D01*
X533600Y-1072000D01*
X533813Y-1072083D01*
X534000Y-1072292D01*
X534080Y-1072583D01*
X534027Y-1072875D01*
X533893Y-1073083D01*
X533733Y-1073167D01*
X533467D01*
X533227Y-1073292D01*
X533067Y-1073542D01*
X533013Y-1073833D01*
X533067Y-1074125D01*
X533200Y-1074333D01*
X533413Y-1074458D01*
X533600Y-1074500D01*
G01X536013Y-1073167D02*
X536120Y-1073042D01*
X536200Y-1072833D01*
X536253Y-1072542D01*
X536200Y-1072292D01*
X536093Y-1072125D01*
X535907Y-1072000D01*
X535187D01*
Y-1074500D01*
X536067D01*
X536253Y-1074333D01*
X536360Y-1074083D01*
X536413Y-1073792D01*
X536360Y-1073500D01*
X536200Y-1073250D01*
X536013Y-1073167D01*
X535187D01*
G01X-457143Y-1211429D02*
Y2242857D01*
X4308572D01*
Y-1211429D01*
X-457143D01*
G01X71650Y-1024800D02*
X69130Y-1024383D01*
X66925Y-1022717D01*
X65035Y-1020217D01*
X63775Y-1017300D01*
X63145Y-1013967D01*
Y-1010633D01*
X63775Y-1007300D01*
X65035Y-1004383D01*
X66925Y-1001884D01*
X69130Y-1000217D01*
X71650Y-999800D01*
X74170Y-1000217D01*
X76375Y-1001884D01*
X78265Y-1004383D01*
X79525Y-1007300D01*
X80155Y-1010633D01*
Y-1013967D01*
X79525Y-1017300D01*
X78265Y-1020217D01*
X76375Y-1022717D01*
X74170Y-1024383D01*
X71650Y-1024800D01*
G01X74170Y-1018133D02*
X77950Y-1024800D01*
G01X91495Y-1008134D02*
Y-1019800D01*
X92755Y-1022717D01*
X94645Y-1024383D01*
X96850Y-1024800D01*
X99055Y-1024383D01*
X100945Y-1022717D01*
X102205Y-1019800D01*
G01Y-1024800D02*
Y-1008134D01*
G01X127720Y-1024800D02*
Y-1008134D01*
G01Y-1011050D02*
X126460Y-1009384D01*
X124570Y-1008550D01*
X122365Y-1008134D01*
X120160Y-1008967D01*
X118270Y-1010633D01*
X117010Y-1013134D01*
X116380Y-1016467D01*
X117010Y-1019800D01*
X118270Y-1022301D01*
X120160Y-1023967D01*
X122365Y-1024800D01*
X124570Y-1024383D01*
X126460Y-1023134D01*
X127720Y-1021467D01*
G01X141895Y-1024800D02*
Y-1008134D01*
G01Y-1012300D02*
X143155Y-1010217D01*
X145045Y-1008550D01*
X147565Y-1008134D01*
X149770Y-1008550D01*
X151660Y-1010217D01*
X152605Y-1013134D01*
Y-1024800D01*
G01X172450Y-999800D02*
Y-1024800D01*
G01X168040Y-1008134D02*
X176860D01*
G01X203320Y-1024800D02*
Y-1008134D01*
G01Y-1011050D02*
X202060Y-1009384D01*
X200170Y-1008550D01*
X197965Y-1008134D01*
X195760Y-1008967D01*
X193870Y-1010633D01*
X192610Y-1013134D01*
X191980Y-1016467D01*
X192610Y-1019800D01*
X193870Y-1022301D01*
X195760Y-1023967D01*
X197965Y-1024800D01*
X200170Y-1024383D01*
X202060Y-1023134D01*
X203320Y-1021467D01*
G01X49820Y-1042350D02*
X51387D01*
Y-1044240D01*
X50917Y-1044870D01*
X50368Y-1045290D01*
X49585Y-1045500D01*
X48802Y-1045290D01*
X48253Y-1044870D01*
X47783Y-1044240D01*
X47470Y-1043505D01*
X47313Y-1042665D01*
Y-1041930D01*
X47470Y-1041300D01*
X47783Y-1040565D01*
X48253Y-1039935D01*
X48723Y-1039515D01*
X49350Y-1039200D01*
X49898D01*
X50525Y-1039410D01*
X50995Y-1039830D01*
G01X53927Y-1039200D02*
Y-1043715D01*
X54240Y-1044660D01*
X54867Y-1045290D01*
X55650Y-1045500D01*
X56433Y-1045290D01*
X57060Y-1044660D01*
X57373Y-1043715D01*
Y-1039200D01*
G01X61010D02*
X62890D01*
G01X61950D02*
Y-1045500D01*
G01X61010D02*
X62890D01*
G01X66605Y-1044660D02*
X67232Y-1045185D01*
X67937Y-1045500D01*
X68563D01*
X69190Y-1045185D01*
X69660Y-1044660D01*
X69895Y-1043925D01*
X69738Y-1043190D01*
X69347Y-1042560D01*
X68642Y-1042140D01*
X67702Y-1041930D01*
X67153Y-1041510D01*
X66918Y-1040775D01*
X67075Y-1040040D01*
X67467Y-1039515D01*
X68015Y-1039200D01*
X68563D01*
X69112Y-1039410D01*
X69582Y-1039935D01*
G01X72905Y-1045500D02*
Y-1039200D01*
G01X76195D02*
Y-1045500D01*
G01Y-1042350D02*
X72905D01*
G01X78892Y-1045500D02*
X80850Y-1039200D01*
X82808Y-1045500D01*
G01X82103Y-1043295D02*
X79597D01*
G01X85348Y-1045500D02*
Y-1039200D01*
X88952Y-1045500D01*
Y-1039200D01*
G01X98027Y-1045500D02*
Y-1039200D01*
X99593D01*
X100220Y-1039515D01*
X100690Y-1039935D01*
X101082Y-1040565D01*
X101395Y-1041300D01*
X101473Y-1042350D01*
X101395Y-1043400D01*
X101082Y-1044135D01*
X100690Y-1044765D01*
X100220Y-1045185D01*
X99593Y-1045500D01*
X98027D01*
G01X105110Y-1039200D02*
X106990D01*
G01X106050D02*
Y-1045500D01*
G01X105110D02*
X106990D01*
G01X110705Y-1044660D02*
X111332Y-1045185D01*
X112037Y-1045500D01*
X112663D01*
X113290Y-1045185D01*
X113760Y-1044660D01*
X113995Y-1043925D01*
X113838Y-1043190D01*
X113447Y-1042560D01*
X112742Y-1042140D01*
X111802Y-1041930D01*
X111253Y-1041510D01*
X111018Y-1040775D01*
X111175Y-1040040D01*
X111567Y-1039515D01*
X112115Y-1039200D01*
X112663D01*
X113212Y-1039410D01*
X113682Y-1039935D01*
G01X118650Y-1039200D02*
Y-1045500D01*
G01X116848Y-1039200D02*
X120452D01*
G01X124950Y-1045710D02*
X124793Y-1045605D01*
Y-1045395D01*
X124950Y-1045290D01*
X125107Y-1045395D01*
Y-1045605D01*
X124950Y-1045710D01*
G01X131093Y-1046655D02*
X131407Y-1045290D01*
G01X137550Y-1039200D02*
Y-1045500D01*
G01X135748Y-1039200D02*
X139352D01*
G01X141892Y-1045500D02*
X143850Y-1039200D01*
X145808Y-1045500D01*
G01X145103Y-1043295D02*
X142597D01*
G01X150150Y-1045500D02*
X149523Y-1045395D01*
X148975Y-1044975D01*
X148505Y-1044345D01*
X148192Y-1043610D01*
X148035Y-1042770D01*
Y-1041930D01*
X148192Y-1041090D01*
X148505Y-1040355D01*
X148975Y-1039725D01*
X149523Y-1039305D01*
X150150Y-1039200D01*
X150777Y-1039305D01*
X151325Y-1039725D01*
X151795Y-1040355D01*
X152108Y-1041090D01*
X152265Y-1041930D01*
Y-1042770D01*
X152108Y-1043610D01*
X151795Y-1044345D01*
X151325Y-1044975D01*
X150777Y-1045395D01*
X150150Y-1045500D01*
G01X156450D02*
Y-1042665D01*
X154883Y-1039200D01*
G01X158017D02*
X156450Y-1042665D01*
G01X161027Y-1039200D02*
Y-1043715D01*
X161340Y-1044660D01*
X161967Y-1045290D01*
X162750Y-1045500D01*
X163533Y-1045290D01*
X164160Y-1044660D01*
X164473Y-1043715D01*
Y-1039200D01*
G01X167092Y-1045500D02*
X169050Y-1039200D01*
X171008Y-1045500D01*
G01X170303Y-1043295D02*
X167797D01*
G01X173548Y-1045500D02*
Y-1039200D01*
X177152Y-1045500D01*
Y-1039200D01*
G01X51073Y-1049725D02*
X50603Y-1049410D01*
X50055Y-1049200D01*
X49428D01*
X48723Y-1049515D01*
X48175Y-1050040D01*
X47783Y-1050670D01*
X47470Y-1051720D01*
X47392Y-1052665D01*
X47548Y-1053610D01*
X47783Y-1054240D01*
X48253Y-1054870D01*
X48802Y-1055290D01*
X49350Y-1055500D01*
X49898D01*
X50447Y-1055290D01*
X50917Y-1054975D01*
X51308Y-1054555D01*
G01X54710Y-1049200D02*
X56590D01*
G01X55650D02*
Y-1055500D01*
G01X54710D02*
X56590D01*
G01X61950Y-1049200D02*
Y-1055500D01*
G01X60148Y-1049200D02*
X63752D01*
G01X68250Y-1055500D02*
Y-1052665D01*
X66683Y-1049200D01*
G01X69817D02*
X68250Y-1052665D01*
G01X79127Y-1054240D02*
X79597Y-1054975D01*
X80223Y-1055395D01*
X80928Y-1055500D01*
X81555Y-1055395D01*
X82182Y-1054870D01*
X82573Y-1054240D01*
X82652Y-1053610D01*
X82495Y-1052875D01*
X81947Y-1052350D01*
X81398Y-1052140D01*
X80693D01*
G01X81398D02*
X81868Y-1051825D01*
X82260Y-1051300D01*
X82417Y-1050670D01*
X82260Y-1050040D01*
X81868Y-1049515D01*
X81163Y-1049200D01*
X80458Y-1049305D01*
X79753Y-1049725D01*
G01X85427Y-1054240D02*
X85897Y-1054975D01*
X86523Y-1055395D01*
X87228Y-1055500D01*
X87855Y-1055395D01*
X88482Y-1054870D01*
X88873Y-1054240D01*
X88952Y-1053610D01*
X88795Y-1052875D01*
X88247Y-1052350D01*
X87698Y-1052140D01*
X86993D01*
G01X87698D02*
X88168Y-1051825D01*
X88560Y-1051300D01*
X88717Y-1050670D01*
X88560Y-1050040D01*
X88168Y-1049515D01*
X87463Y-1049200D01*
X86758Y-1049305D01*
X86053Y-1049725D01*
G01X91727Y-1054240D02*
X92197Y-1054975D01*
X92823Y-1055395D01*
X93528Y-1055500D01*
X94155Y-1055395D01*
X94782Y-1054870D01*
X95173Y-1054240D01*
X95252Y-1053610D01*
X95095Y-1052875D01*
X94547Y-1052350D01*
X93998Y-1052140D01*
X93293D01*
G01X93998D02*
X94468Y-1051825D01*
X94860Y-1051300D01*
X95017Y-1050670D01*
X94860Y-1050040D01*
X94468Y-1049515D01*
X93763Y-1049200D01*
X93058Y-1049305D01*
X92353Y-1049725D01*
G01X99593Y-1055500D02*
X99750Y-1054135D01*
X99985Y-1052980D01*
X100298Y-1051930D01*
X100690Y-1050775D01*
X101317Y-1049200D01*
X98183D01*
G01X105893Y-1055500D02*
X106050Y-1054135D01*
X106285Y-1052980D01*
X106598Y-1051930D01*
X106990Y-1050775D01*
X107617Y-1049200D01*
X104483D01*
G01X112193Y-1056655D02*
X112507Y-1055290D01*
G01X118650Y-1049200D02*
Y-1055500D01*
G01X116848Y-1049200D02*
X120452D01*
G01X122992Y-1055500D02*
X124950Y-1049200D01*
X126908Y-1055500D01*
G01X126203Y-1053295D02*
X123697D01*
G01X130310Y-1049200D02*
X132190D01*
G01X131250D02*
Y-1055500D01*
G01X130310D02*
X132190D01*
G01X135200Y-1049200D02*
X136297Y-1055500D01*
X137550Y-1049200D01*
X138803Y-1055500D01*
X139900Y-1049200D01*
G01X141892Y-1055500D02*
X143850Y-1049200D01*
X145808Y-1055500D01*
G01X145103Y-1053295D02*
X142597D01*
G01X148348Y-1055500D02*
Y-1049200D01*
X151952Y-1055500D01*
Y-1049200D01*
G01X162358Y-1057600D02*
X161575Y-1056550D01*
X161183Y-1055500D01*
Y-1051300D01*
X161575Y-1050250D01*
X162358Y-1049200D01*
G01X173783Y-1055500D02*
Y-1049200D01*
X175742D01*
X176368Y-1049515D01*
X176760Y-1049935D01*
X176917Y-1050775D01*
X176760Y-1051615D01*
X176290Y-1052140D01*
X175742Y-1052455D01*
X173783D01*
G01X175742D02*
X176917Y-1055500D01*
G01X181650Y-1055710D02*
X181493Y-1055605D01*
Y-1055395D01*
X181650Y-1055290D01*
X181807Y-1055395D01*
Y-1055605D01*
X181650Y-1055710D01*
G01X187950Y-1055500D02*
X187323Y-1055395D01*
X186775Y-1054975D01*
X186305Y-1054345D01*
X185992Y-1053610D01*
X185835Y-1052770D01*
Y-1051930D01*
X185992Y-1051090D01*
X186305Y-1050355D01*
X186775Y-1049725D01*
X187323Y-1049305D01*
X187950Y-1049200D01*
X188577Y-1049305D01*
X189125Y-1049725D01*
X189595Y-1050355D01*
X189908Y-1051090D01*
X190065Y-1051930D01*
Y-1052770D01*
X189908Y-1053610D01*
X189595Y-1054345D01*
X189125Y-1054975D01*
X188577Y-1055395D01*
X187950Y-1055500D01*
G01X194250Y-1055710D02*
X194093Y-1055605D01*
Y-1055395D01*
X194250Y-1055290D01*
X194407Y-1055395D01*
Y-1055605D01*
X194250Y-1055710D01*
G01X202273Y-1049725D02*
X201803Y-1049410D01*
X201255Y-1049200D01*
X200628D01*
X199923Y-1049515D01*
X199375Y-1050040D01*
X198983Y-1050670D01*
X198670Y-1051720D01*
X198592Y-1052665D01*
X198748Y-1053610D01*
X198983Y-1054240D01*
X199453Y-1054870D01*
X200002Y-1055290D01*
X200550Y-1055500D01*
X201098D01*
X201647Y-1055290D01*
X202117Y-1054975D01*
X202508Y-1054555D01*
G01X206850Y-1055710D02*
X206693Y-1055605D01*
Y-1055395D01*
X206850Y-1055290D01*
X207007Y-1055395D01*
Y-1055605D01*
X206850Y-1055710D01*
G01X213542Y-1057600D02*
X214325Y-1056550D01*
X214717Y-1055500D01*
Y-1051300D01*
X214325Y-1050250D01*
X213542Y-1049200D01*
G01X47548Y-1035500D02*
Y-1029200D01*
X51152Y-1035500D01*
Y-1029200D01*
G01X55650Y-1035500D02*
X55023Y-1035395D01*
X54475Y-1034975D01*
X54005Y-1034345D01*
X53692Y-1033610D01*
X53535Y-1032770D01*
Y-1031930D01*
X53692Y-1031090D01*
X54005Y-1030355D01*
X54475Y-1029725D01*
X55023Y-1029305D01*
X55650Y-1029200D01*
X56277Y-1029305D01*
X56825Y-1029725D01*
X57295Y-1030355D01*
X57608Y-1031090D01*
X57765Y-1031930D01*
Y-1032770D01*
X57608Y-1033610D01*
X57295Y-1034345D01*
X56825Y-1034975D01*
X56277Y-1035395D01*
X55650Y-1035500D01*
G01X61950Y-1035710D02*
X61793Y-1035605D01*
Y-1035395D01*
X61950Y-1035290D01*
X62107Y-1035395D01*
Y-1035605D01*
X61950Y-1035710D01*
G01X66762Y-1030250D02*
X67232Y-1029620D01*
X67780Y-1029305D01*
X68407Y-1029200D01*
X69190Y-1029410D01*
X69738Y-1029935D01*
X69895Y-1030565D01*
X69817Y-1031195D01*
X69503Y-1031720D01*
X67937Y-1032770D01*
X67232Y-1033505D01*
X66762Y-1034555D01*
X66605Y-1035500D01*
X69895D01*
G01X74550D02*
Y-1029200D01*
X73610Y-1030460D01*
G01Y-1035500D02*
X75490D01*
G01X80850D02*
Y-1029200D01*
X79910Y-1030460D01*
G01Y-1035500D02*
X81790D01*
G01X86993Y-1036655D02*
X87307Y-1035290D01*
G01X91100Y-1029200D02*
X92197Y-1035500D01*
X93450Y-1029200D01*
X94703Y-1035500D01*
X95800Y-1029200D01*
G01X101317Y-1035500D02*
X98183D01*
Y-1029200D01*
X101317D01*
G01X100063Y-1032245D02*
X98183D01*
G01X104248Y-1035500D02*
Y-1029200D01*
X107852Y-1035500D01*
Y-1029200D01*
G01X110705Y-1035500D02*
Y-1029200D01*
G01X113995D02*
Y-1035500D01*
G01Y-1032350D02*
X110705D01*
G01X116927Y-1029200D02*
Y-1033715D01*
X117240Y-1034660D01*
X117867Y-1035290D01*
X118650Y-1035500D01*
X119433Y-1035290D01*
X120060Y-1034660D01*
X120373Y-1033715D01*
Y-1029200D01*
G01X122992Y-1035500D02*
X124950Y-1029200D01*
X126908Y-1035500D01*
G01X126203Y-1033295D02*
X123697D01*
G01X136062Y-1030250D02*
X136532Y-1029620D01*
X137080Y-1029305D01*
X137707Y-1029200D01*
X138490Y-1029410D01*
X139038Y-1029935D01*
X139195Y-1030565D01*
X139117Y-1031195D01*
X138803Y-1031720D01*
X137237Y-1032770D01*
X136532Y-1033505D01*
X136062Y-1034555D01*
X135905Y-1035500D01*
X139195D01*
G01X142048D02*
Y-1029200D01*
X145652Y-1035500D01*
Y-1029200D01*
G01X148427Y-1035500D02*
Y-1029200D01*
X149993D01*
X150620Y-1029515D01*
X151090Y-1029935D01*
X151482Y-1030565D01*
X151795Y-1031300D01*
X151873Y-1032350D01*
X151795Y-1033400D01*
X151482Y-1034135D01*
X151090Y-1034765D01*
X150620Y-1035185D01*
X149993Y-1035500D01*
X148427D01*
G01X161183D02*
Y-1029200D01*
X163142D01*
X163768Y-1029515D01*
X164160Y-1029935D01*
X164317Y-1030775D01*
X164160Y-1031615D01*
X163690Y-1032140D01*
X163142Y-1032455D01*
X161183D01*
G01X163142D02*
X164317Y-1035500D01*
G01X167327D02*
Y-1029200D01*
X168893D01*
X169520Y-1029515D01*
X169990Y-1029935D01*
X170382Y-1030565D01*
X170695Y-1031300D01*
X170773Y-1032350D01*
X170695Y-1033400D01*
X170382Y-1034135D01*
X169990Y-1034765D01*
X169520Y-1035185D01*
X168893Y-1035500D01*
X167327D01*
G01X175350Y-1035710D02*
X175193Y-1035605D01*
Y-1035395D01*
X175350Y-1035290D01*
X175507Y-1035395D01*
Y-1035605D01*
X175350Y-1035710D01*
G01X243000Y-1004500D02*
Y-1012500D01*
X247000D01*
G01X254800D02*
Y-1007167D01*
G01Y-1008100D02*
X254400Y-1007567D01*
X253800Y-1007300D01*
X253100Y-1007167D01*
X252400Y-1007433D01*
X251800Y-1007967D01*
X251400Y-1008767D01*
X251200Y-1009833D01*
X251400Y-1010900D01*
X251800Y-1011700D01*
X252400Y-1012233D01*
X253100Y-1012500D01*
X253800Y-1012367D01*
X254400Y-1011967D01*
X254800Y-1011434D01*
G01X258900Y-1014900D02*
X259500Y-1015167D01*
X260300Y-1014900D01*
X260800Y-1014367D01*
X261200Y-1013700D01*
X261800Y-1011567D01*
X263100Y-1007167D01*
G01X259900D02*
X261800Y-1011567D01*
G01X267500Y-1008900D02*
X270700D01*
X270400Y-1007967D01*
X269900Y-1007433D01*
X269200Y-1007167D01*
X268500Y-1007300D01*
X267900Y-1007700D01*
X267500Y-1008633D01*
X267300Y-1009434D01*
Y-1010233D01*
X267500Y-1011033D01*
X268000Y-1011833D01*
X268600Y-1012367D01*
X269300Y-1012500D01*
X270000Y-1012233D01*
X270700Y-1011434D01*
G01X275600Y-1012500D02*
Y-1007167D01*
G01Y-1008233D02*
X276100Y-1007700D01*
X276600Y-1007300D01*
X277300Y-1007167D01*
X277800Y-1007300D01*
X278400Y-1007700D01*
G01X262100Y-1054500D02*
X265900D01*
X262100Y-1062500D01*
X265900D01*
G01X272000Y-1057167D02*
Y-1062500D01*
G01Y-1055033D02*
X271800Y-1054900D01*
Y-1054633D01*
X272000Y-1054500D01*
X272200Y-1054633D01*
Y-1054900D01*
X272000Y-1055033D01*
G01X278700Y-1059833D02*
X281300D01*
G01X286200Y-1065167D02*
Y-1057167D01*
G01Y-1058367D02*
X286700Y-1057700D01*
X287200Y-1057300D01*
X288000Y-1057167D01*
X288700Y-1057300D01*
X289400Y-1057967D01*
X289700Y-1058900D01*
X289800Y-1059833D01*
X289700Y-1060767D01*
X289400Y-1061700D01*
X288800Y-1062233D01*
X288000Y-1062500D01*
X287300Y-1062367D01*
X286600Y-1061967D01*
X286200Y-1061434D01*
G01X296000Y-1057167D02*
Y-1062500D01*
G01Y-1055033D02*
X295800Y-1054900D01*
Y-1054633D01*
X296000Y-1054500D01*
X296200Y-1054633D01*
Y-1054900D01*
X296000Y-1055033D01*
G01X302300Y-1062500D02*
Y-1057167D01*
G01Y-1058500D02*
X302700Y-1057833D01*
X303300Y-1057300D01*
X304100Y-1057167D01*
X304800Y-1057300D01*
X305400Y-1057833D01*
X305700Y-1058767D01*
Y-1062500D01*
G01X310600Y-1064500D02*
X311300Y-1065033D01*
X312100Y-1065167D01*
X312800Y-1065033D01*
X313400Y-1064367D01*
X313800Y-1063433D01*
Y-1057167D01*
G01Y-1058233D02*
X313400Y-1057700D01*
X312800Y-1057300D01*
X312100Y-1057167D01*
X311300Y-1057433D01*
X310800Y-1057967D01*
X310400Y-1058900D01*
X310200Y-1059833D01*
X310300Y-1060633D01*
X310700Y-1061567D01*
X311300Y-1062233D01*
X312100Y-1062500D01*
X312700Y-1062367D01*
X313400Y-1061833D01*
X313800Y-1061300D01*
G01X271500Y-1029500D02*
X274000Y-1037500D01*
X276500Y-1029500D01*
G01X284200Y-1030167D02*
X283600Y-1029767D01*
X282900Y-1029500D01*
X282100D01*
X281200Y-1029900D01*
X280500Y-1030567D01*
X280000Y-1031367D01*
X279600Y-1032700D01*
X279500Y-1033900D01*
X279700Y-1035100D01*
X280000Y-1035900D01*
X280600Y-1036700D01*
X281300Y-1037233D01*
X282000Y-1037500D01*
X282700D01*
X283400Y-1037233D01*
X284000Y-1036833D01*
X284500Y-1036300D01*
G01X292200Y-1030167D02*
X291600Y-1029767D01*
X290900Y-1029500D01*
X290100D01*
X289200Y-1029900D01*
X288500Y-1030567D01*
X288000Y-1031367D01*
X287600Y-1032700D01*
X287500Y-1033900D01*
X287700Y-1035100D01*
X288000Y-1035900D01*
X288600Y-1036700D01*
X289300Y-1037233D01*
X290000Y-1037500D01*
X290700D01*
X291400Y-1037233D01*
X292000Y-1036833D01*
X292500Y-1036300D01*
G01X294300Y-1011300D02*
X294900Y-1011967D01*
X295600Y-1012367D01*
X296500Y-1012500D01*
X297400Y-1012233D01*
X298100Y-1011700D01*
X298600Y-1010767D01*
X298700Y-1009700D01*
X298500Y-1008633D01*
X298000Y-1007967D01*
X297300Y-1007433D01*
X296600Y-1007300D01*
X295900Y-1007433D01*
X295000Y-1007967D01*
X295300Y-1004500D01*
X298000D01*
G01X369600Y-1055833D02*
X370200Y-1055033D01*
X370900Y-1054633D01*
X371700Y-1054500D01*
X372700Y-1054767D01*
X373400Y-1055433D01*
X373600Y-1056233D01*
X373500Y-1057034D01*
X373100Y-1057700D01*
X371100Y-1059033D01*
X370200Y-1059967D01*
X369600Y-1061300D01*
X369400Y-1062500D01*
X373600D01*
G01X379500Y-1054500D02*
X378700Y-1054767D01*
X378100Y-1055433D01*
X377700Y-1056233D01*
X377400Y-1057300D01*
X377300Y-1058500D01*
X377400Y-1059700D01*
X377700Y-1060767D01*
X378100Y-1061567D01*
X378700Y-1062233D01*
X379500Y-1062500D01*
X380300Y-1062233D01*
X380900Y-1061567D01*
X381300Y-1060767D01*
X381600Y-1059700D01*
X381700Y-1058500D01*
X381600Y-1057300D01*
X381300Y-1056233D01*
X380900Y-1055433D01*
X380300Y-1054767D01*
X379500Y-1054500D01*
G01X385600Y-1055833D02*
X386200Y-1055033D01*
X386900Y-1054633D01*
X387700Y-1054500D01*
X388700Y-1054767D01*
X389400Y-1055433D01*
X389600Y-1056233D01*
X389500Y-1057034D01*
X389100Y-1057700D01*
X387100Y-1059033D01*
X386200Y-1059967D01*
X385600Y-1061300D01*
X385400Y-1062500D01*
X389600D01*
G01X393600Y-1055833D02*
X394200Y-1055033D01*
X394900Y-1054633D01*
X395700Y-1054500D01*
X396700Y-1054767D01*
X397400Y-1055433D01*
X397600Y-1056233D01*
X397500Y-1057034D01*
X397100Y-1057700D01*
X395100Y-1059033D01*
X394200Y-1059967D01*
X393600Y-1061300D01*
X393400Y-1062500D01*
X397600D01*
G01X401700Y-1062767D02*
X405300Y-1054500D01*
G01X411500Y-1062500D02*
Y-1054500D01*
X410300Y-1056100D01*
G01Y-1062500D02*
X412700D01*
G01X417600Y-1055833D02*
X418200Y-1055033D01*
X418900Y-1054633D01*
X419700Y-1054500D01*
X420700Y-1054767D01*
X421400Y-1055433D01*
X421600Y-1056233D01*
X421500Y-1057034D01*
X421100Y-1057700D01*
X419100Y-1059033D01*
X418200Y-1059967D01*
X417600Y-1061300D01*
X417400Y-1062500D01*
X421600D01*
G01X425700Y-1062767D02*
X429300Y-1054500D01*
G01X435500Y-1062500D02*
Y-1054500D01*
X434300Y-1056100D01*
G01Y-1062500D02*
X436700D01*
G01X441300Y-1060900D02*
X441900Y-1061833D01*
X442700Y-1062367D01*
X443600Y-1062500D01*
X444400Y-1062367D01*
X445200Y-1061700D01*
X445700Y-1060900D01*
X445800Y-1060100D01*
X445600Y-1059167D01*
X444900Y-1058500D01*
X444200Y-1058233D01*
X443300D01*
G01X444200D02*
X444800Y-1057833D01*
X445300Y-1057167D01*
X445500Y-1056367D01*
X445300Y-1055567D01*
X444800Y-1054900D01*
X443900Y-1054500D01*
X443000Y-1054633D01*
X442100Y-1055167D01*
G01X369300Y-1040000D02*
Y-1032000D01*
X371300D01*
X372100Y-1032400D01*
X372700Y-1032933D01*
X373200Y-1033733D01*
X373600Y-1034667D01*
X373700Y-1036000D01*
X373600Y-1037333D01*
X373200Y-1038267D01*
X372700Y-1039067D01*
X372100Y-1039600D01*
X371300Y-1040000D01*
X369300D01*
G01X377000D02*
X379500Y-1032000D01*
X382000Y-1040000D01*
G01X381100Y-1037200D02*
X377900D01*
G01X385600Y-1040000D02*
Y-1032000D01*
X389400D01*
G01X388000Y-1035867D02*
X385600D01*
G01X395500Y-1032000D02*
X394700Y-1032267D01*
X394100Y-1032933D01*
X393700Y-1033733D01*
X393400Y-1034800D01*
X393300Y-1036000D01*
X393400Y-1037200D01*
X393700Y-1038267D01*
X394100Y-1039067D01*
X394700Y-1039733D01*
X395500Y-1040000D01*
X396300Y-1039733D01*
X396900Y-1039067D01*
X397300Y-1038267D01*
X397600Y-1037200D01*
X397700Y-1036000D01*
X397600Y-1034800D01*
X397300Y-1033733D01*
X396900Y-1032933D01*
X396300Y-1032267D01*
X395500Y-1032000D01*
G01X403500D02*
Y-1040000D01*
G01X401200Y-1032000D02*
X405800D01*
G01X409500Y-1040000D02*
Y-1032000D01*
X411900D01*
X412700Y-1032400D01*
X413300Y-1033333D01*
X413500Y-1034400D01*
X413300Y-1035467D01*
X412800Y-1036267D01*
X411900Y-1036667D01*
X409500D01*
G01X420300Y-1035733D02*
X420700Y-1035333D01*
X421000Y-1034667D01*
X421200Y-1033733D01*
X421000Y-1032933D01*
X420600Y-1032400D01*
X419900Y-1032000D01*
X417200D01*
Y-1040000D01*
X420500D01*
X421200Y-1039467D01*
X421600Y-1038667D01*
X421800Y-1037733D01*
X421600Y-1036800D01*
X421000Y-1036000D01*
X420300Y-1035733D01*
X417200D01*
G01X427500Y-1040000D02*
Y-1032000D01*
X426300Y-1033600D01*
G01Y-1040000D02*
X428700D01*
G01X433000D02*
X435500Y-1032000D01*
X438000Y-1040000D01*
G01X437100Y-1037200D02*
X433900D01*
G01X441600Y-1040000D02*
Y-1032000D01*
X445400D01*
G01X444000Y-1035867D02*
X441600D01*
G01X451500Y-1032000D02*
X450700Y-1032267D01*
X450100Y-1032933D01*
X449700Y-1033733D01*
X449400Y-1034800D01*
X449300Y-1036000D01*
X449400Y-1037200D01*
X449700Y-1038267D01*
X450100Y-1039067D01*
X450700Y-1039733D01*
X451500Y-1040000D01*
X452300Y-1039733D01*
X452900Y-1039067D01*
X453300Y-1038267D01*
X453600Y-1037200D01*
X453700Y-1036000D01*
X453600Y-1034800D01*
X453300Y-1033733D01*
X452900Y-1032933D01*
X452300Y-1032267D01*
X451500Y-1032000D01*
G01X389600Y-1012500D02*
Y-1004500D01*
X393400D01*
G01X392000Y-1008367D02*
X389600D01*
G01X399500Y-1004500D02*
X398700Y-1004767D01*
X398100Y-1005433D01*
X397700Y-1006233D01*
X397400Y-1007300D01*
X397300Y-1008500D01*
X397400Y-1009700D01*
X397700Y-1010767D01*
X398100Y-1011567D01*
X398700Y-1012233D01*
X399500Y-1012500D01*
X400300Y-1012233D01*
X400900Y-1011567D01*
X401300Y-1010767D01*
X401600Y-1009700D01*
X401700Y-1008500D01*
X401600Y-1007300D01*
X401300Y-1006233D01*
X400900Y-1005433D01*
X400300Y-1004767D01*
X399500Y-1004500D01*
G01X407500D02*
Y-1012500D01*
G01X405200Y-1004500D02*
X409800D01*
G01X412500Y-1015167D02*
X418500D01*
G01X421500Y-1012500D02*
Y-1004500D01*
X423900D01*
X424700Y-1004900D01*
X425300Y-1005833D01*
X425500Y-1006900D01*
X425300Y-1007967D01*
X424800Y-1008767D01*
X423900Y-1009167D01*
X421500D01*
G01X429300Y-1012500D02*
Y-1004500D01*
X431300D01*
X432100Y-1004900D01*
X432700Y-1005433D01*
X433200Y-1006233D01*
X433600Y-1007167D01*
X433700Y-1008500D01*
X433600Y-1009833D01*
X433200Y-1010767D01*
X432700Y-1011567D01*
X432100Y-1012100D01*
X431300Y-1012500D01*
X429300D01*
G01X440300Y-1008233D02*
X440700Y-1007833D01*
X441000Y-1007167D01*
X441200Y-1006233D01*
X441000Y-1005433D01*
X440600Y-1004900D01*
X439900Y-1004500D01*
X437200D01*
Y-1012500D01*
X440500D01*
X441200Y-1011967D01*
X441600Y-1011167D01*
X441800Y-1010233D01*
X441600Y-1009300D01*
X441000Y-1008500D01*
X440300Y-1008233D01*
X437200D01*
G01X444500Y-1015167D02*
X450500D01*
G01X456300Y-1008233D02*
X456700Y-1007833D01*
X457000Y-1007167D01*
X457200Y-1006233D01*
X457000Y-1005433D01*
X456600Y-1004900D01*
X455900Y-1004500D01*
X453200D01*
Y-1012500D01*
X456500D01*
X457200Y-1011967D01*
X457600Y-1011167D01*
X457800Y-1010233D01*
X457600Y-1009300D01*
X457000Y-1008500D01*
X456300Y-1008233D01*
X453200D01*
G01X461300Y-1012500D02*
Y-1004500D01*
X463300D01*
X464100Y-1004900D01*
X464700Y-1005433D01*
X465200Y-1006233D01*
X465600Y-1007167D01*
X465700Y-1008500D01*
X465600Y-1009833D01*
X465200Y-1010767D01*
X464700Y-1011567D01*
X464100Y-1012100D01*
X463300Y-1012500D01*
X461300D01*
G01X468500Y-1015167D02*
X474500D01*
G01X480100Y-1008500D02*
X482100D01*
Y-1010900D01*
X481500Y-1011700D01*
X480800Y-1012233D01*
X479800Y-1012500D01*
X478800Y-1012233D01*
X478100Y-1011700D01*
X477500Y-1010900D01*
X477100Y-1009967D01*
X476900Y-1008900D01*
Y-1007967D01*
X477100Y-1007167D01*
X477500Y-1006233D01*
X478100Y-1005433D01*
X478700Y-1004900D01*
X479500Y-1004500D01*
X480200D01*
X481000Y-1004767D01*
X481600Y-1005300D01*
G01X485500Y-1012500D02*
Y-1004500D01*
X487900D01*
X488700Y-1004900D01*
X489300Y-1005833D01*
X489500Y-1006900D01*
X489300Y-1007967D01*
X488800Y-1008767D01*
X487900Y-1009167D01*
X485500D01*
G01X493300Y-1004500D02*
Y-1010233D01*
X493700Y-1011434D01*
X494500Y-1012233D01*
X495500Y-1012500D01*
X496500Y-1012233D01*
X497300Y-1011434D01*
X497700Y-1010233D01*
Y-1004500D01*
G01X458000Y-1065500D02*
Y-1057500D01*
X456800Y-1059100D01*
G01Y-1065500D02*
X459200D01*
G01X464100Y-1062167D02*
X464800Y-1061233D01*
X465400Y-1060700D01*
X466200Y-1060433D01*
X466900Y-1060700D01*
X467400Y-1061233D01*
X467800Y-1062033D01*
X467900Y-1062967D01*
X467800Y-1063767D01*
X467400Y-1064567D01*
X466800Y-1065233D01*
X466100Y-1065500D01*
X465300Y-1065233D01*
X464600Y-1064434D01*
X464200Y-1063233D01*
X464100Y-1061900D01*
X464300Y-1060167D01*
X464600Y-1059233D01*
X465100Y-1058300D01*
X465800Y-1057633D01*
X466500Y-1057500D01*
X467200Y-1057767D01*
X467700Y-1058433D01*
G01X474000Y-1065767D02*
X473800Y-1065633D01*
Y-1065367D01*
X474000Y-1065233D01*
X474200Y-1065367D01*
Y-1065633D01*
X474000Y-1065767D01*
G01X480100Y-1062167D02*
X480800Y-1061233D01*
X481400Y-1060700D01*
X482200Y-1060433D01*
X482900Y-1060700D01*
X483400Y-1061233D01*
X483800Y-1062033D01*
X483900Y-1062967D01*
X483800Y-1063767D01*
X483400Y-1064567D01*
X482800Y-1065233D01*
X482100Y-1065500D01*
X481300Y-1065233D01*
X480600Y-1064434D01*
X480200Y-1063233D01*
X480100Y-1061900D01*
X480300Y-1060167D01*
X480600Y-1059233D01*
X481100Y-1058300D01*
X481800Y-1057633D01*
X482500Y-1057500D01*
X483200Y-1057767D01*
X483700Y-1058433D01*
G01X503000Y-1065500D02*
Y-1057500D01*
X501800Y-1059100D01*
G01Y-1065500D02*
X504200D01*
G01X510800D02*
X511000Y-1063767D01*
X511300Y-1062300D01*
X511700Y-1060967D01*
X512200Y-1059500D01*
X513000Y-1057500D01*
X509000D01*
G01X519000Y-1065767D02*
X518800Y-1065633D01*
Y-1065367D01*
X519000Y-1065233D01*
X519200Y-1065367D01*
Y-1065633D01*
X519000Y-1065767D01*
G01X525100Y-1058833D02*
X525700Y-1058033D01*
X526400Y-1057633D01*
X527200Y-1057500D01*
X528200Y-1057767D01*
X528900Y-1058433D01*
X529100Y-1059233D01*
X529000Y-1060034D01*
X528600Y-1060700D01*
X526600Y-1062033D01*
X525700Y-1062967D01*
X525100Y-1064300D01*
X524900Y-1065500D01*
X529100D01*
G01X523100Y-1040500D02*
Y-1032500D01*
X526900D01*
G01X525500Y-1036367D02*
X523100D01*
M02*
